FILE_TYPE = MACRO_DRAWING;
SET COLOR_WIRE YELLOW;
SET COLOR_PROP ORANGE;
SET COLOR_DOT WHITE;
SET COLOR_ARC YELLOW;
SET COLOR_BODY GREEN;
SET COLOR_NOTE PURPLE;
SET PROP_DISPLAY VALUE;
SET PAGE_NUMBER P175;
FORCEADD OFFPAGE..1
(-8800 1650);
FORCEPROP 2 LAST $XR0 81 
J 0
(-9081 1650);
DISPLAY 0.638298 (-9081 1650);
PAINT MONO (-9081 1650);
FORCEPROP 1 LAST COMMENT_BODY TRUE
J 0
(-8675 1550);
DISPLAY 0.872340 (-8675 1550);
PAINT GREEN (-8675 1550);
DISPLAY INVISIBLE (-8675 1550);
FORCEPROP 1 LAST OFFPAGE TRUE
J 0
(-8475 1525);
DISPLAY 0.872340 (-8475 1525);
PAINT GREEN (-8475 1525);
DISPLAY INVISIBLE (-8475 1525);
FORCEPROP 2 LAST CDS_LIB standard
J 0
(-8800 1650);
DISPLAY INVISIBLE (-8800 1650);
FORCEPROP 2 LAST PATH I1
J 0
(-9075 1700);
DISPLAY 0.680851 (-9075 1700);
DISPLAY INVISIBLE (-9075 1700);
FORCEADD VCC_CORE..1
(-7325 1000);
FORCEPROP 3 LASTPIN (-7325 950) SIG_NAME P5V_AUX\g
J 0
(-7315 960);
DISPLAY 0.659574 (-7315 960);
PAINT MONO (-7315 960);
DISPLAY INVISIBLE (-7315 960);
FORCEPROP 1 LAST HDL_POWER P5V_AUX
J 1
(-7325 1050);
DISPLAY 0.489362 (-7325 1050);
PAINT GREEN (-7325 1050);
FORCEPROP 2 LAST CDS_LIB pure_quanta_power
J 0
(-7325 1000);
DISPLAY INVISIBLE (-7325 1000);
FORCEPROP 1 LAST PATH I10
J 0
(-7275 1025);
DISPLAY 0.872340 (-7275 1025);
PAINT AQUA (-7275 1025);
DISPLAY INVISIBLE (-7275 1025);
FORCEADD Q_CAP..1
(-2750 6125);
FORCEPROP 1 LAST LOCATION PC75
J 0
(-2700 6250);
DISPLAY 0.489362 (-2700 6250);
PAINT SKYBLUE (-2700 6250);
FORCEPROP 0 LAST $SEC 1
J 0
(-2700 6300);
DISPLAY 0.680851 (-2700 6300);
PAINT MONO (-2700 6300);
DISPLAY INVISIBLE (-2700 6300);
FORCEPROP 0 LAST CDS_SEC 1
J 0
(-2700 6300);
DISPLAY 1.021277 (-2700 6300);
DISPLAY INVISIBLE (-2700 6300);
FORCEPROP 1 LASTPIN (-2750 6225) $PN 1
J 0
(-2740 6205);
DISPLAY 0.489362 (-2740 6205);
PAINT MONO (-2740 6205);
FORCEPROP 1 LASTPIN (-2750 6025) $PN 2
J 0
(-2740 6005);
DISPLAY 0.489362 (-2740 6005);
PAINT MONO (-2740 6005);
FORCEPROP 1 LAST PACK_TYPE C0402
J 0
(-2700 6000);
DISPLAY 0.489362 (-2700 6000);
PAINT SKYBLUE (-2700 6000);
FORCEPROP 1 LAST MATERIAL X6S
J 0
(-2700 6050);
DISPLAY 0.489362 (-2700 6050);
PAINT SKYBLUE (-2700 6050);
FORCEPROP 1 LAST TOLERANCE 10%
J 0
(-2700 6100);
DISPLAY 0.489362 (-2700 6100);
PAINT SKYBLUE (-2700 6100);
FORCEPROP 1 LAST VALUE 1UF
J 0
(-2700 6200);
DISPLAY 0.489362 (-2700 6200);
PAINT SKYBLUE (-2700 6200);
FORCEPROP 1 LAST VOLTAGE 16V
J 0
(-2700 6150);
DISPLAY 0.489362 (-2700 6150);
PAINT SKYBLUE (-2700 6150);
FORCEPROP 1 LAST PART_NUMBER CH5103KEB01
J 0
(-2700 5950);
DISPLAY 0.489362 (-2700 5950);
PAINT SKYBLUE (-2700 5950);
DISPLAY INVISIBLE (-2700 5950);
FORCEPROP 2 LAST CDS_LIB pure_quanta
J 0
(-2750 6125);
DISPLAY INVISIBLE (-2750 6125);
FORCEPROP 1 LAST PATH I100
J 0
(-2700 6275);
DISPLAY 0.978723 (-2700 6275);
PAINT WHITE (-2700 6275);
DISPLAY INVISIBLE (-2700 6275);
FORCEADD OFFPAGE..4
(-2150 1100);
FORCEPROP 2 LAST $XR0 201 
J 0
(-1964 1100);
DISPLAY 0.638298 (-1964 1100);
PAINT MONO (-1964 1100);
FORCEPROP 2 LAST $XR1 202 
J 0
(-1844 1100);
DISPLAY 0.638298 (-1844 1100);
PAINT MONO (-1844 1100);
FORCEPROP 2 LAST $XR2 203 
J 0
(-1724 1100);
DISPLAY 0.638298 (-1724 1100);
PAINT MONO (-1724 1100);
FORCEPROP 1 LAST COMMENT_BODY TRUE
J 0
(-2175 1000);
DISPLAY 0.872340 (-2175 1000);
PAINT GREEN (-2175 1000);
DISPLAY INVISIBLE (-2175 1000);
FORCEPROP 1 LAST OFFPAGE TRUE
J 0
(-1825 975);
DISPLAY 0.872340 (-1825 975);
PAINT GREEN (-1825 975);
DISPLAY INVISIBLE (-1825 975);
FORCEPROP 2 LAST CDS_LIB standard
J 0
(-2150 1100);
DISPLAY INVISIBLE (-2150 1100);
FORCEPROP 2 LAST PATH I101
J 0
(-1700 1150);
DISPLAY 0.680851 (-1700 1150);
DISPLAY INVISIBLE (-1700 1150);
FORCEADD OFFPAGE..4
(-2300 1900);
FORCEPROP 2 LAST $XR0 205 
J 0
(-2114 1900);
DISPLAY 0.638298 (-2114 1900);
PAINT MONO (-2114 1900);
FORCEPROP 1 LAST COMMENT_BODY TRUE
J 0
(-2325 1800);
DISPLAY 0.872340 (-2325 1800);
PAINT GREEN (-2325 1800);
DISPLAY INVISIBLE (-2325 1800);
FORCEPROP 1 LAST OFFPAGE TRUE
J 0
(-1975 1775);
DISPLAY 0.872340 (-1975 1775);
PAINT GREEN (-1975 1775);
DISPLAY INVISIBLE (-1975 1775);
FORCEPROP 2 LAST CDS_LIB standard
J 0
(-2300 1900);
DISPLAY INVISIBLE (-2300 1900);
FORCEPROP 2 LAST PATH I102
J 0
(-2100 1950);
DISPLAY 0.680851 (-2100 1950);
DISPLAY INVISIBLE (-2100 1950);
FORCEADD OFFPAGE..2
(-2300 2000);
FORCEPROP 2 LAST $XR0 205 
J 0
(-2111 2000);
DISPLAY 0.638298 (-2111 2000);
PAINT MONO (-2111 2000);
FORCEPROP 1 LAST COMMENT_BODY TRUE
J 0
(-2345 1905);
DISPLAY 0.872340 (-2345 1905);
PAINT GREEN (-2345 1905);
DISPLAY INVISIBLE (-2345 1905);
FORCEPROP 1 LAST OFFPAGE TRUE
J 0
(-1975 1875);
DISPLAY 0.872340 (-1975 1875);
PAINT GREEN (-1975 1875);
DISPLAY INVISIBLE (-1975 1875);
FORCEPROP 2 LAST CDS_LIB standard
J 0
(-2300 2000);
DISPLAY INVISIBLE (-2300 2000);
FORCEPROP 2 LAST PATH I103
J 0
(-2100 2050);
DISPLAY 0.680851 (-2100 2050);
DISPLAY INVISIBLE (-2100 2050);
FORCEADD OFFPAGE..4
(-2150 1700);
FORCEPROP 2 LAST $XR0 205 
J 0
(-1964 1700);
DISPLAY 0.638298 (-1964 1700);
PAINT MONO (-1964 1700);
FORCEPROP 2 LAST $XR1 206 
J 0
(-1844 1700);
DISPLAY 0.638298 (-1844 1700);
PAINT MONO (-1844 1700);
FORCEPROP 1 LAST COMMENT_BODY TRUE
J 0
(-2175 1600);
DISPLAY 0.872340 (-2175 1600);
PAINT GREEN (-2175 1600);
DISPLAY INVISIBLE (-2175 1600);
FORCEPROP 1 LAST OFFPAGE TRUE
J 0
(-1825 1575);
DISPLAY 0.872340 (-1825 1575);
PAINT GREEN (-1825 1575);
DISPLAY INVISIBLE (-1825 1575);
FORCEPROP 2 LAST CDS_LIB standard
J 0
(-2150 1700);
DISPLAY INVISIBLE (-2150 1700);
FORCEPROP 2 LAST PATH I104
J 0
(-1825 1750);
DISPLAY 0.680851 (-1825 1750);
DISPLAY INVISIBLE (-1825 1750);
FORCEADD OFFPAGE..4
(-2300 2200);
FORCEPROP 2 LAST $XR0 205 
J 0
(-2114 2200);
DISPLAY 0.638298 (-2114 2200);
PAINT MONO (-2114 2200);
FORCEPROP 1 LAST COMMENT_BODY TRUE
J 0
(-2325 2100);
DISPLAY 0.872340 (-2325 2100);
PAINT GREEN (-2325 2100);
DISPLAY INVISIBLE (-2325 2100);
FORCEPROP 1 LAST OFFPAGE TRUE
J 0
(-1975 2075);
DISPLAY 0.872340 (-1975 2075);
PAINT GREEN (-1975 2075);
DISPLAY INVISIBLE (-1975 2075);
FORCEPROP 2 LAST CDS_LIB standard
J 0
(-2300 2200);
DISPLAY INVISIBLE (-2300 2200);
FORCEPROP 2 LAST PATH I105
J 0
(-2100 2250);
DISPLAY 0.680851 (-2100 2250);
DISPLAY INVISIBLE (-2100 2250);
FORCEADD OFFPAGE..2
(-2300 2300);
FORCEPROP 2 LAST $XR0 205 
J 0
(-2111 2300);
DISPLAY 0.638298 (-2111 2300);
PAINT MONO (-2111 2300);
FORCEPROP 1 LAST COMMENT_BODY TRUE
J 0
(-2345 2205);
DISPLAY 0.872340 (-2345 2205);
PAINT GREEN (-2345 2205);
DISPLAY INVISIBLE (-2345 2205);
FORCEPROP 1 LAST OFFPAGE TRUE
J 0
(-1975 2175);
DISPLAY 0.872340 (-1975 2175);
PAINT GREEN (-1975 2175);
DISPLAY INVISIBLE (-1975 2175);
FORCEPROP 2 LAST CDS_LIB standard
J 0
(-2300 2300);
DISPLAY INVISIBLE (-2300 2300);
FORCEPROP 2 LAST PATH I106
J 0
(-2100 2350);
DISPLAY 0.680851 (-2100 2350);
DISPLAY INVISIBLE (-2100 2350);
FORCEADD OFFPAGE..4
(-2300 2500);
FORCEPROP 2 LAST $XR0 206 
J 0
(-2114 2500);
DISPLAY 0.638298 (-2114 2500);
PAINT MONO (-2114 2500);
FORCEPROP 1 LAST COMMENT_BODY TRUE
J 0
(-2325 2400);
DISPLAY 0.872340 (-2325 2400);
PAINT GREEN (-2325 2400);
DISPLAY INVISIBLE (-2325 2400);
FORCEPROP 1 LAST OFFPAGE TRUE
J 0
(-1975 2375);
DISPLAY 0.872340 (-1975 2375);
PAINT GREEN (-1975 2375);
DISPLAY INVISIBLE (-1975 2375);
FORCEPROP 2 LAST CDS_LIB standard
J 0
(-2300 2500);
DISPLAY INVISIBLE (-2300 2500);
FORCEPROP 2 LAST PATH I107
J 0
(-2100 2550);
DISPLAY 0.680851 (-2100 2550);
DISPLAY INVISIBLE (-2100 2550);
FORCEADD OFFPAGE..2
(-2300 2600);
FORCEPROP 2 LAST $XR0 206 
J 0
(-2111 2600);
DISPLAY 0.638298 (-2111 2600);
PAINT MONO (-2111 2600);
FORCEPROP 1 LAST COMMENT_BODY TRUE
J 0
(-2345 2505);
DISPLAY 0.872340 (-2345 2505);
PAINT GREEN (-2345 2505);
DISPLAY INVISIBLE (-2345 2505);
FORCEPROP 1 LAST OFFPAGE TRUE
J 0
(-1975 2475);
DISPLAY 0.872340 (-1975 2475);
PAINT GREEN (-1975 2475);
DISPLAY INVISIBLE (-1975 2475);
FORCEPROP 2 LAST CDS_LIB standard
J 0
(-2300 2600);
DISPLAY INVISIBLE (-2300 2600);
FORCEPROP 2 LAST PATH I108
J 0
(-2100 2650);
DISPLAY 0.680851 (-2100 2650);
DISPLAY INVISIBLE (-2100 2650);
FORCEADD OFFPAGE..4
(-2325 2800);
FORCEPROP 2 LAST $XR0 206 
J 0
(-2139 2800);
DISPLAY 0.638298 (-2139 2800);
PAINT MONO (-2139 2800);
FORCEPROP 1 LAST COMMENT_BODY TRUE
J 0
(-2350 2700);
DISPLAY 0.872340 (-2350 2700);
PAINT GREEN (-2350 2700);
DISPLAY INVISIBLE (-2350 2700);
FORCEPROP 1 LAST OFFPAGE TRUE
J 0
(-2000 2675);
DISPLAY 0.872340 (-2000 2675);
PAINT GREEN (-2000 2675);
DISPLAY INVISIBLE (-2000 2675);
FORCEPROP 2 LAST CDS_LIB standard
J 0
(-2325 2800);
DISPLAY INVISIBLE (-2325 2800);
FORCEPROP 2 LAST PATH I109
J 0
(-2125 2850);
DISPLAY 0.680851 (-2125 2850);
DISPLAY INVISIBLE (-2125 2850);
FORCEADD VCC_CORE..1
(-6850 1300);
FORCEPROP 3 LASTPIN (-6850 1250) SIG_NAME P3V3_AUX\g
J 0
(-6840 1260);
DISPLAY 0.659574 (-6840 1260);
PAINT MONO (-6840 1260);
DISPLAY INVISIBLE (-6840 1260);
FORCEPROP 1 LAST HDL_POWER P3V3_AUX
J 1
(-6850 1350);
DISPLAY 0.489362 (-6850 1350);
PAINT GREEN (-6850 1350);
FORCEPROP 2 LAST CDS_LIB pure_quanta_power
J 0
(-6850 1300);
DISPLAY INVISIBLE (-6850 1300);
FORCEPROP 1 LAST PATH I11
J 0
(-6800 1325);
DISPLAY 0.872340 (-6800 1325);
PAINT AQUA (-6800 1325);
DISPLAY INVISIBLE (-6800 1325);
FORCEADD OFFPAGE..2
(-2325 2900);
FORCEPROP 2 LAST $XR0 206 
J 0
(-2136 2900);
DISPLAY 0.638298 (-2136 2900);
PAINT MONO (-2136 2900);
FORCEPROP 1 LAST COMMENT_BODY TRUE
J 0
(-2370 2805);
DISPLAY 0.872340 (-2370 2805);
PAINT GREEN (-2370 2805);
DISPLAY INVISIBLE (-2370 2805);
FORCEPROP 1 LAST OFFPAGE TRUE
J 0
(-2000 2775);
DISPLAY 0.872340 (-2000 2775);
PAINT GREEN (-2000 2775);
DISPLAY INVISIBLE (-2000 2775);
FORCEPROP 2 LAST CDS_LIB standard
J 0
(-2325 2900);
DISPLAY INVISIBLE (-2325 2900);
FORCEPROP 2 LAST PATH I110
J 0
(-2125 2950);
DISPLAY 0.680851 (-2125 2950);
DISPLAY INVISIBLE (-2125 2950);
FORCEADD UNIVERSAL_GND..1
(-2225 3025);
FORCEPROP 3 LASTPIN (-2225 3075) SIG_NAME GND\g
J 0
(-2215 3085);
DISPLAY 0.659574 (-2215 3085);
PAINT MONO (-2215 3085);
DISPLAY INVISIBLE (-2215 3085);
FORCEPROP 1 LAST HDL_POWER GND
J 1
(-2200 2950);
DISPLAY 0.872340 (-2200 2950);
PAINT GREEN (-2200 2950);
DISPLAY INVISIBLE (-2200 2950);
FORCEPROP 2 LAST CDS_LIB pure_quanta_power
J 0
(-2225 3025);
DISPLAY INVISIBLE (-2225 3025);
FORCEPROP 1 LAST PATH I111
J 0
(-2150 3025);
DISPLAY 0.872340 (-2150 3025);
PAINT AQUA (-2150 3025);
DISPLAY INVISIBLE (-2150 3025);
FORCEADD UNIVERSAL_GND..1
(-2225 3325);
FORCEPROP 3 LASTPIN (-2225 3375) SIG_NAME GND\g
J 0
(-2215 3385);
DISPLAY 0.659574 (-2215 3385);
PAINT MONO (-2215 3385);
DISPLAY INVISIBLE (-2215 3385);
FORCEPROP 1 LAST HDL_POWER GND
J 1
(-2200 3250);
DISPLAY 0.872340 (-2200 3250);
PAINT GREEN (-2200 3250);
DISPLAY INVISIBLE (-2200 3250);
FORCEPROP 2 LAST CDS_LIB pure_quanta_power
J 0
(-2225 3325);
DISPLAY INVISIBLE (-2225 3325);
FORCEPROP 1 LAST PATH I112
J 0
(-2150 3325);
DISPLAY 0.872340 (-2150 3325);
PAINT AQUA (-2150 3325);
DISPLAY INVISIBLE (-2150 3325);
FORCEADD OFFPAGE..4
(-2325 3700);
FORCEPROP 2 LAST $XR0 203 
J 0
(-2139 3700);
DISPLAY 0.638298 (-2139 3700);
PAINT MONO (-2139 3700);
FORCEPROP 1 LAST COMMENT_BODY TRUE
J 0
(-2350 3600);
DISPLAY 0.872340 (-2350 3600);
PAINT GREEN (-2350 3600);
DISPLAY INVISIBLE (-2350 3600);
FORCEPROP 1 LAST OFFPAGE TRUE
J 0
(-2000 3575);
DISPLAY 0.872340 (-2000 3575);
PAINT GREEN (-2000 3575);
DISPLAY INVISIBLE (-2000 3575);
FORCEPROP 2 LAST CDS_LIB standard
J 0
(-2325 3700);
DISPLAY INVISIBLE (-2325 3700);
FORCEPROP 2 LAST PATH I113
J 0
(-2125 3750);
DISPLAY 0.680851 (-2125 3750);
DISPLAY INVISIBLE (-2125 3750);
FORCEADD OFFPAGE..2
(-2300 3800);
FORCEPROP 2 LAST $XR0 203 
J 0
(-2111 3800);
DISPLAY 0.638298 (-2111 3800);
PAINT MONO (-2111 3800);
FORCEPROP 1 LAST COMMENT_BODY TRUE
J 0
(-2345 3705);
DISPLAY 0.872340 (-2345 3705);
PAINT GREEN (-2345 3705);
DISPLAY INVISIBLE (-2345 3705);
FORCEPROP 1 LAST OFFPAGE TRUE
J 0
(-1975 3675);
DISPLAY 0.872340 (-1975 3675);
PAINT GREEN (-1975 3675);
DISPLAY INVISIBLE (-1975 3675);
FORCEPROP 2 LAST CDS_LIB standard
J 0
(-2300 3800);
DISPLAY INVISIBLE (-2300 3800);
FORCEPROP 2 LAST PATH I114
J 0
(-2100 3850);
DISPLAY 0.680851 (-2100 3850);
DISPLAY INVISIBLE (-2100 3850);
FORCEADD OFFPAGE..4
(-2300 4000);
FORCEPROP 2 LAST $XR0 203 
J 0
(-2114 4000);
DISPLAY 0.638298 (-2114 4000);
PAINT MONO (-2114 4000);
FORCEPROP 1 LAST COMMENT_BODY TRUE
J 0
(-2325 3900);
DISPLAY 0.872340 (-2325 3900);
PAINT GREEN (-2325 3900);
DISPLAY INVISIBLE (-2325 3900);
FORCEPROP 1 LAST OFFPAGE TRUE
J 0
(-1975 3875);
DISPLAY 0.872340 (-1975 3875);
PAINT GREEN (-1975 3875);
DISPLAY INVISIBLE (-1975 3875);
FORCEPROP 2 LAST CDS_LIB standard
J 0
(-2300 4000);
DISPLAY INVISIBLE (-2300 4000);
FORCEPROP 2 LAST PATH I115
J 0
(-2100 4050);
DISPLAY 0.680851 (-2100 4050);
DISPLAY INVISIBLE (-2100 4050);
FORCEADD OFFPAGE..2
(-2300 4100);
FORCEPROP 2 LAST $XR0 203 
J 0
(-2111 4100);
DISPLAY 0.638298 (-2111 4100);
PAINT MONO (-2111 4100);
FORCEPROP 1 LAST COMMENT_BODY TRUE
J 0
(-2345 4005);
DISPLAY 0.872340 (-2345 4005);
PAINT GREEN (-2345 4005);
DISPLAY INVISIBLE (-2345 4005);
FORCEPROP 1 LAST OFFPAGE TRUE
J 0
(-1975 3975);
DISPLAY 0.872340 (-1975 3975);
PAINT GREEN (-1975 3975);
DISPLAY INVISIBLE (-1975 3975);
FORCEPROP 2 LAST CDS_LIB standard
J 0
(-2300 4100);
DISPLAY INVISIBLE (-2300 4100);
FORCEPROP 2 LAST PATH I116
J 0
(-2100 4150);
DISPLAY 0.680851 (-2100 4150);
DISPLAY INVISIBLE (-2100 4150);
FORCEADD OFFPAGE..4
(-2300 4300);
FORCEPROP 2 LAST $XR0 202 
J 0
(-2114 4300);
DISPLAY 0.638298 (-2114 4300);
PAINT MONO (-2114 4300);
FORCEPROP 1 LAST COMMENT_BODY TRUE
J 0
(-2325 4200);
DISPLAY 0.872340 (-2325 4200);
PAINT GREEN (-2325 4200);
DISPLAY INVISIBLE (-2325 4200);
FORCEPROP 1 LAST OFFPAGE TRUE
J 0
(-1975 4175);
DISPLAY 0.872340 (-1975 4175);
PAINT GREEN (-1975 4175);
DISPLAY INVISIBLE (-1975 4175);
FORCEPROP 2 LAST CDS_LIB standard
J 0
(-2300 4300);
DISPLAY INVISIBLE (-2300 4300);
FORCEPROP 2 LAST PATH I117
J 0
(-2100 4350);
DISPLAY 0.680851 (-2100 4350);
DISPLAY INVISIBLE (-2100 4350);
FORCEADD OFFPAGE..2
(-2300 4400);
FORCEPROP 2 LAST $XR0 202 
J 0
(-2111 4400);
DISPLAY 0.638298 (-2111 4400);
PAINT MONO (-2111 4400);
FORCEPROP 1 LAST COMMENT_BODY TRUE
J 0
(-2345 4305);
DISPLAY 0.872340 (-2345 4305);
PAINT GREEN (-2345 4305);
DISPLAY INVISIBLE (-2345 4305);
FORCEPROP 1 LAST OFFPAGE TRUE
J 0
(-1975 4275);
DISPLAY 0.872340 (-1975 4275);
PAINT GREEN (-1975 4275);
DISPLAY INVISIBLE (-1975 4275);
FORCEPROP 2 LAST CDS_LIB standard
J 0
(-2300 4400);
DISPLAY INVISIBLE (-2300 4400);
FORCEPROP 2 LAST PATH I118
J 0
(-2100 4450);
DISPLAY 0.680851 (-2100 4450);
DISPLAY INVISIBLE (-2100 4450);
FORCEADD OFFPAGE..4
(-2300 4600);
FORCEPROP 2 LAST $XR0 202 
J 0
(-2114 4600);
DISPLAY 0.638298 (-2114 4600);
PAINT MONO (-2114 4600);
FORCEPROP 1 LAST COMMENT_BODY TRUE
J 0
(-2325 4500);
DISPLAY 0.872340 (-2325 4500);
PAINT GREEN (-2325 4500);
DISPLAY INVISIBLE (-2325 4500);
FORCEPROP 1 LAST OFFPAGE TRUE
J 0
(-1975 4475);
DISPLAY 0.872340 (-1975 4475);
PAINT GREEN (-1975 4475);
DISPLAY INVISIBLE (-1975 4475);
FORCEPROP 2 LAST CDS_LIB standard
J 0
(-2300 4600);
DISPLAY INVISIBLE (-2300 4600);
FORCEPROP 2 LAST PATH I119
J 0
(-2100 4650);
DISPLAY 0.680851 (-2100 4650);
DISPLAY INVISIBLE (-2100 4650);
FORCEADD Q_RES..2
(-6950 1600);
FORCEPROP 1 LAST LOCATION PR67
J 0
(-6900 1650);
DISPLAY 0.489362 (-6900 1650);
PAINT SKYBLUE (-6900 1650);
FORCEPROP 0 LAST $SEC 1
J 0
(-6925 1675);
DISPLAY 0.680851 (-6925 1675);
PAINT MONO (-6925 1675);
DISPLAY INVISIBLE (-6925 1675);
FORCEPROP 0 LAST CDS_SEC 1
J 0
(-6925 1675);
DISPLAY 1.021277 (-6925 1675);
DISPLAY INVISIBLE (-6925 1675);
FORCEPROP 1 LASTPIN (-6950 1700) $PN 1
J 0
(-6945 1662);
DISPLAY 0.489362 (-6945 1662);
PAINT MONO (-6945 1662);
FORCEPROP 1 LASTPIN (-6950 1500) $PN 2
J 0
(-6945 1510);
DISPLAY 0.489362 (-6945 1510);
PAINT MONO (-6945 1510);
FORCEPROP 1 LAST VALUE 1.96K
J 0
(-6900 1625);
DISPLAY 0.489362 (-6900 1625);
PAINT SKYBLUE (-6900 1625);
FORCEPROP 1 LAST TOLERANCE 1%
J 0
(-6900 1600);
DISPLAY 0.489362 (-6900 1600);
PAINT SKYBLUE (-6900 1600);
FORCEPROP 1 LAST PACK_TYPE 0402LF
J 0
(-6900 1500);
DISPLAY 0.489362 (-6900 1500);
PAINT SKYBLUE (-6900 1500);
FORCEPROP 1 LAST MATERIAL CHIP
J 0
(-6900 1550);
DISPLAY 0.489362 (-6900 1550);
PAINT SKYBLUE (-6900 1550);
FORCEPROP 1 LAST WATTAGE 1/16W
J 0
(-6900 1575);
DISPLAY 0.489362 (-6900 1575);
PAINT SKYBLUE (-6900 1575);
FORCEPROP 1 LAST PART_NUMBER CS21962FB05
J 0
(-6900 1525);
DISPLAY 0.489362 (-6900 1525);
PAINT SKYBLUE (-6900 1525);
DISPLAY INVISIBLE (-6900 1525);
FORCEPROP 2 LAST CDS_LIB pure_quanta
J 0
(-6950 1600);
DISPLAY INVISIBLE (-6950 1600);
FORCEPROP 1 LAST PATH I12
J 0
(-6900 1775);
DISPLAY 0.978723 (-6900 1775);
PAINT WHITE (-6900 1775);
DISPLAY INVISIBLE (-6900 1775);
FORCEADD OFFPAGE..2
(-2300 4700);
FORCEPROP 2 LAST $XR0 202 
J 0
(-2111 4700);
DISPLAY 0.638298 (-2111 4700);
PAINT MONO (-2111 4700);
FORCEPROP 1 LAST COMMENT_BODY TRUE
J 0
(-2345 4605);
DISPLAY 0.872340 (-2345 4605);
PAINT GREEN (-2345 4605);
DISPLAY INVISIBLE (-2345 4605);
FORCEPROP 1 LAST OFFPAGE TRUE
J 0
(-1975 4575);
DISPLAY 0.872340 (-1975 4575);
PAINT GREEN (-1975 4575);
DISPLAY INVISIBLE (-1975 4575);
FORCEPROP 2 LAST CDS_LIB standard
J 0
(-2300 4700);
DISPLAY INVISIBLE (-2300 4700);
FORCEPROP 2 LAST PATH I120
J 0
(-2100 4750);
DISPLAY 0.680851 (-2100 4750);
DISPLAY INVISIBLE (-2100 4750);
FORCEADD OFFPAGE..4
(-2300 4900);
FORCEPROP 2 LAST $XR0 201 
J 0
(-2114 4900);
DISPLAY 0.638298 (-2114 4900);
PAINT MONO (-2114 4900);
FORCEPROP 1 LAST COMMENT_BODY TRUE
J 0
(-2325 4800);
DISPLAY 0.872340 (-2325 4800);
PAINT GREEN (-2325 4800);
DISPLAY INVISIBLE (-2325 4800);
FORCEPROP 1 LAST OFFPAGE TRUE
J 0
(-1975 4775);
DISPLAY 0.872340 (-1975 4775);
PAINT GREEN (-1975 4775);
DISPLAY INVISIBLE (-1975 4775);
FORCEPROP 2 LAST CDS_LIB standard
J 0
(-2300 4900);
DISPLAY INVISIBLE (-2300 4900);
FORCEPROP 2 LAST PATH I121
J 0
(-2100 4950);
DISPLAY 0.680851 (-2100 4950);
DISPLAY INVISIBLE (-2100 4950);
FORCEADD OFFPAGE..2
(-2300 5000);
FORCEPROP 2 LAST $XR0 201 
J 0
(-2111 5000);
DISPLAY 0.638298 (-2111 5000);
PAINT MONO (-2111 5000);
FORCEPROP 1 LAST COMMENT_BODY TRUE
J 0
(-2345 4905);
DISPLAY 0.872340 (-2345 4905);
PAINT GREEN (-2345 4905);
DISPLAY INVISIBLE (-2345 4905);
FORCEPROP 1 LAST OFFPAGE TRUE
J 0
(-1975 4875);
DISPLAY 0.872340 (-1975 4875);
PAINT GREEN (-1975 4875);
DISPLAY INVISIBLE (-1975 4875);
FORCEPROP 2 LAST CDS_LIB standard
J 0
(-2300 5000);
DISPLAY INVISIBLE (-2300 5000);
FORCEPROP 2 LAST PATH I122
J 0
(-2100 5050);
DISPLAY 0.680851 (-2100 5050);
DISPLAY INVISIBLE (-2100 5050);
FORCEADD OFFPAGE..4
(-2300 5200);
FORCEPROP 2 LAST $XR0 201 
J 0
(-2114 5200);
DISPLAY 0.638298 (-2114 5200);
PAINT MONO (-2114 5200);
FORCEPROP 1 LAST COMMENT_BODY TRUE
J 0
(-2325 5100);
DISPLAY 0.872340 (-2325 5100);
PAINT GREEN (-2325 5100);
DISPLAY INVISIBLE (-2325 5100);
FORCEPROP 1 LAST OFFPAGE TRUE
J 0
(-1975 5075);
DISPLAY 0.872340 (-1975 5075);
PAINT GREEN (-1975 5075);
DISPLAY INVISIBLE (-1975 5075);
FORCEPROP 2 LAST CDS_LIB standard
J 0
(-2300 5200);
DISPLAY INVISIBLE (-2300 5200);
FORCEPROP 2 LAST PATH I123
J 0
(-2100 5250);
DISPLAY 0.680851 (-2100 5250);
DISPLAY INVISIBLE (-2100 5250);
FORCEADD OFFPAGE..2
(-2300 5300);
FORCEPROP 2 LAST $XR0 201 
J 0
(-2111 5300);
DISPLAY 0.638298 (-2111 5300);
PAINT MONO (-2111 5300);
FORCEPROP 1 LAST COMMENT_BODY TRUE
J 0
(-2345 5205);
DISPLAY 0.872340 (-2345 5205);
PAINT GREEN (-2345 5205);
DISPLAY INVISIBLE (-2345 5205);
FORCEPROP 1 LAST OFFPAGE TRUE
J 0
(-1975 5175);
DISPLAY 0.872340 (-1975 5175);
PAINT GREEN (-1975 5175);
DISPLAY INVISIBLE (-1975 5175);
FORCEPROP 2 LAST CDS_LIB standard
J 0
(-2300 5300);
DISPLAY INVISIBLE (-2300 5300);
FORCEPROP 2 LAST PATH I124
J 0
(-2100 5350);
DISPLAY 0.680851 (-2100 5350);
DISPLAY INVISIBLE (-2100 5350);
FORCEADD OFFPAGE..2
(-2075 5825);
FORCEPROP 2 LAST $XR0 201 
J 0
(-1886 5825);
DISPLAY 0.638298 (-1886 5825);
PAINT MONO (-1886 5825);
FORCEPROP 2 LAST $XR1 202 
J 0
(-1766 5825);
DISPLAY 0.638298 (-1766 5825);
PAINT MONO (-1766 5825);
FORCEPROP 2 LAST $XR2 203 
J 0
(-1646 5825);
DISPLAY 0.638298 (-1646 5825);
PAINT MONO (-1646 5825);
FORCEPROP 2 LAST $XR3 205 
J 0
(-1526 5825);
DISPLAY 0.638298 (-1526 5825);
PAINT MONO (-1526 5825);
FORCEPROP 2 LAST $XR4 206 
J 0
(-1406 5825);
DISPLAY 0.638298 (-1406 5825);
PAINT MONO (-1406 5825);
FORCEPROP 1 LAST COMMENT_BODY TRUE
J 0
(-2120 5730);
DISPLAY 0.872340 (-2120 5730);
PAINT GREEN (-2120 5730);
DISPLAY INVISIBLE (-2120 5730);
FORCEPROP 1 LAST OFFPAGE TRUE
J 0
(-1750 5700);
DISPLAY 0.872340 (-1750 5700);
PAINT GREEN (-1750 5700);
DISPLAY INVISIBLE (-1750 5700);
FORCEPROP 2 LAST CDS_LIB standard
J 0
(-2075 5825);
DISPLAY INVISIBLE (-2075 5825);
FORCEPROP 2 LAST PATH I125
J 0
(-1400 5875);
DISPLAY 0.680851 (-1400 5875);
DISPLAY INVISIBLE (-1400 5875);
FORCEADD Q_RES..1
(-2300 6300);
FORCEPROP 1 LAST LOCATION PR76
J 0
(-2525 6300);
DISPLAY 0.489362 (-2525 6300);
PAINT SKYBLUE (-2525 6300);
FORCEPROP 0 LAST $SEC 1
J 0
(-2350 6400);
DISPLAY 0.680851 (-2350 6400);
PAINT MONO (-2350 6400);
DISPLAY INVISIBLE (-2350 6400);
FORCEPROP 0 LAST CDS_SEC 1
J 0
(-2350 6400);
DISPLAY 1.021277 (-2350 6400);
DISPLAY INVISIBLE (-2350 6400);
FORCEPROP 1 LASTPIN (-2400 6300) $PN 1
J 0
(-2388 6312);
DISPLAY 0.489362 (-2388 6312);
PAINT MONO (-2388 6312);
FORCEPROP 1 LASTPIN (-2200 6300) $PN 2
J 0
(-2238 6312);
DISPLAY 0.489362 (-2238 6312);
PAINT MONO (-2238 6312);
FORCEPROP 1 LAST PACK_TYPE 0402LF
J 0
(-2150 6200);
DISPLAY 0.489362 (-2150 6200);
PAINT SKYBLUE (-2150 6200);
FORCEPROP 1 LAST TOLERANCE 1%
J 0
(-2100 6325);
DISPLAY 0.489362 (-2100 6325);
PAINT SKYBLUE (-2100 6325);
FORCEPROP 1 LAST MATERIAL CHIP
J 0
(-2000 6325);
DISPLAY 0.489362 (-2000 6325);
PAINT SKYBLUE (-2000 6325);
FORCEPROP 1 LAST VALUE 1
J 2
(-2125 6325);
DISPLAY 0.489362 (-2125 6325);
PAINT SKYBLUE (-2125 6325);
FORCEPROP 1 LAST WATTAGE 1/16W
J 2
(-1850 6200);
DISPLAY 0.489362 (-1850 6200);
PAINT SKYBLUE (-1850 6200);
FORCEPROP 1 LAST PART_NUMBER CS-1002FB04
J 0
(-2150 6250);
DISPLAY 0.489362 (-2150 6250);
PAINT SKYBLUE (-2150 6250);
DISPLAY INVISIBLE (-2150 6250);
FORCEPROP 2 LAST CDS_LIB pure_quanta
J 0
(-2300 6300);
DISPLAY INVISIBLE (-2300 6300);
FORCEPROP 1 LAST PATH I126
J 0
(-2350 6450);
DISPLAY 0.978723 (-2350 6450);
PAINT WHITE (-2350 6450);
DISPLAY INVISIBLE (-2350 6450);
FORCEADD VCC_CORE..1
(-1775 6425);
FORCEPROP 3 LASTPIN (-1775 6375) SIG_NAME P3V3_AUX\g
J 0
(-1765 6385);
DISPLAY 0.659574 (-1765 6385);
PAINT MONO (-1765 6385);
DISPLAY INVISIBLE (-1765 6385);
FORCEPROP 1 LAST HDL_POWER P3V3_AUX
J 1
(-1775 6475);
DISPLAY 0.489362 (-1775 6475);
PAINT GREEN (-1775 6475);
FORCEPROP 2 LAST CDS_LIB pure_quanta_power
J 0
(-1775 6425);
DISPLAY INVISIBLE (-1775 6425);
FORCEPROP 1 LAST PATH I127
J 0
(-1725 6450);
DISPLAY 0.872340 (-1725 6450);
PAINT AQUA (-1725 6450);
DISPLAY INVISIBLE (-1725 6450);
FORCEADD RAA229620GNPHA0..1
(-4100 3550);
FORCEPROP 1 LAST LOCATION PU12
J 0
(-4650 6575);
DISPLAY 0.489362 (-4650 6575);
PAINT SKYBLUE (-4650 6575);
FORCEPROP 0 LAST $SEC 1
J 0
(-4650 6600);
DISPLAY 0.680851 (-4650 6600);
PAINT MONO (-4650 6600);
DISPLAY INVISIBLE (-4650 6600);
FORCEPROP 0 LAST CDS_SEC 1
J 0
(-4650 6600);
DISPLAY 1.021277 (-4650 6600);
DISPLAY INVISIBLE (-4650 6600);
FORCEPROP 0 LASTPIN (-3450 1900) $PN 38
J 0
(-3440 1910);
DISPLAY 0.489362 (-3440 1910);
PAINT MONO (-3440 1910);
FORCEPROP 0 LASTPIN (-3450 2200) $PN 37
J 0
(-3440 2210);
DISPLAY 0.489362 (-3440 2210);
PAINT MONO (-3440 2210);
FORCEPROP 0 LASTPIN (-3450 2500) $PN 36
J 0
(-3440 2510);
DISPLAY 0.489362 (-3440 2510);
PAINT MONO (-3440 2510);
FORCEPROP 0 LASTPIN (-3450 2800) $PN 35
J 0
(-3440 2810);
DISPLAY 0.489362 (-3440 2810);
PAINT MONO (-3440 2810);
FORCEPROP 0 LASTPIN (-3450 3100) $PN 34
J 0
(-3440 3110);
DISPLAY 0.489362 (-3440 3110);
PAINT MONO (-3440 3110);
FORCEPROP 0 LASTPIN (-3450 3400) $PN 33
J 0
(-3440 3410);
DISPLAY 0.489362 (-3440 3410);
PAINT MONO (-3440 3410);
FORCEPROP 0 LASTPIN (-3450 3700) $PN 32
J 0
(-3440 3710);
DISPLAY 0.489362 (-3440 3710);
PAINT MONO (-3440 3710);
FORCEPROP 0 LASTPIN (-3450 4000) $PN 31
J 0
(-3440 4010);
DISPLAY 0.489362 (-3440 4010);
PAINT MONO (-3440 4010);
FORCEPROP 0 LASTPIN (-3450 4300) $PN 30
J 0
(-3440 4310);
DISPLAY 0.489362 (-3440 4310);
PAINT MONO (-3440 4310);
FORCEPROP 0 LASTPIN (-3450 4600) $PN 29
J 0
(-3440 4610);
DISPLAY 0.489362 (-3440 4610);
PAINT MONO (-3440 4610);
FORCEPROP 0 LASTPIN (-3450 4900) $PN 28
J 0
(-3440 4910);
DISPLAY 0.489362 (-3440 4910);
PAINT MONO (-3440 4910);
FORCEPROP 0 LASTPIN (-3450 5200) $PN 27
J 0
(-3440 5210);
DISPLAY 0.489362 (-3440 5210);
PAINT MONO (-3440 5210);
FORCEPROP 0 LASTPIN (-4800 6150) $PN 17
J 2
(-4810 6160);
DISPLAY 0.489362 (-4810 6160);
PAINT MONO (-4810 6160);
FORCEPROP 0 LASTPIN (-4800 1550) $PN 42
J 2
(-4810 1560);
DISPLAY 0.489362 (-4810 1560);
PAINT MONO (-4810 1560);
FORCEPROP 0 LASTPIN (-4800 4850) $PN 15
J 2
(-4810 4860);
DISPLAY 0.489362 (-4810 4860);
PAINT MONO (-4810 4860);
FORCEPROP 0 LASTPIN (-4800 2300) $PN 41
J 2
(-4810 2310);
DISPLAY 0.489362 (-4810 2310);
PAINT MONO (-4810 2310);
FORCEPROP 0 LASTPIN (-4800 6300) $PN 16
J 2
(-4810 6310);
DISPLAY 0.489362 (-4810 6310);
PAINT MONO (-4810 6310);
FORCEPROP 0 LASTPIN (-4800 1050) $PN 20
J 2
(-4810 1060);
DISPLAY 0.489362 (-4810 1060);
PAINT MONO (-4810 1060);
FORCEPROP 0 LASTPIN (-4800 5150) $PN 14
J 2
(-4810 5160);
DISPLAY 0.489362 (-4810 5160);
PAINT MONO (-4810 5160);
FORCEPROP 0 LASTPIN (-4800 5000) $PN 13
J 2
(-4810 5010);
DISPLAY 0.489362 (-4810 5010);
PAINT MONO (-4810 5010);
FORCEPROP 0 LASTPIN (-3450 2000) $PN 1
J 0
(-3440 2010);
DISPLAY 0.489362 (-3440 2010);
PAINT MONO (-3440 2010);
FORCEPROP 0 LASTPIN (-3450 2300) $PN 2
J 0
(-3440 2310);
DISPLAY 0.489362 (-3440 2310);
PAINT MONO (-3440 2310);
FORCEPROP 0 LASTPIN (-3450 2600) $PN 3
J 0
(-3440 2610);
DISPLAY 0.489362 (-3440 2610);
PAINT MONO (-3440 2610);
FORCEPROP 0 LASTPIN (-3450 2900) $PN 4
J 0
(-3440 2910);
DISPLAY 0.489362 (-3440 2910);
PAINT MONO (-3440 2910);
FORCEPROP 0 LASTPIN (-3450 3200) $PN 5
J 0
(-3440 3210);
DISPLAY 0.489362 (-3440 3210);
PAINT MONO (-3440 3210);
FORCEPROP 0 LASTPIN (-3450 3500) $PN 6
J 0
(-3440 3510);
DISPLAY 0.489362 (-3440 3510);
PAINT MONO (-3440 3510);
FORCEPROP 0 LASTPIN (-3450 3800) $PN 7
J 0
(-3440 3810);
DISPLAY 0.489362 (-3440 3810);
PAINT MONO (-3440 3810);
FORCEPROP 0 LASTPIN (-3450 4100) $PN 8
J 0
(-3440 4110);
DISPLAY 0.489362 (-3440 4110);
PAINT MONO (-3440 4110);
FORCEPROP 0 LASTPIN (-3450 4400) $PN 9
J 0
(-3440 4410);
DISPLAY 0.489362 (-3440 4410);
PAINT MONO (-3440 4410);
FORCEPROP 0 LASTPIN (-3450 4700) $PN 10
J 0
(-3440 4710);
DISPLAY 0.489362 (-3440 4710);
PAINT MONO (-3440 4710);
FORCEPROP 0 LASTPIN (-3450 5000) $PN 11
J 0
(-3440 5010);
DISPLAY 0.489362 (-3440 5010);
PAINT MONO (-3440 5010);
FORCEPROP 0 LASTPIN (-3450 5300) $PN 12
J 0
(-3440 5310);
DISPLAY 0.489362 (-3440 5310);
PAINT MONO (-3440 5310);
FORCEPROP 0 LASTPIN (-4800 2450) $PN 18
J 2
(-4810 2460);
DISPLAY 0.489362 (-4810 2460);
PAINT MONO (-4810 2460);
FORCEPROP 0 LASTPIN (-4800 4000) $PN 26
J 2
(-4810 4010);
DISPLAY 0.489362 (-4810 4010);
PAINT MONO (-4810 4010);
FORCEPROP 0 LASTPIN (-4800 2900) $PN 39
J 2
(-4810 2910);
DISPLAY 0.489362 (-4810 2910);
PAINT MONO (-4810 2910);
FORCEPROP 0 LASTPIN (-4800 5850) $PN 22
J 2
(-4810 5860);
DISPLAY 0.489362 (-4810 5860);
PAINT MONO (-4810 5860);
FORCEPROP 0 LASTPIN (-4800 5700) $PN 21
J 2
(-4810 5710);
DISPLAY 0.489362 (-4810 5710);
PAINT MONO (-4810 5710);
FORCEPROP 0 LASTPIN (-4800 5400) $PN 24
J 2
(-4810 5410);
DISPLAY 0.489362 (-4810 5410);
PAINT MONO (-4810 5410);
FORCEPROP 0 LASTPIN (-4800 5550) $PN 23
J 2
(-4810 5560);
DISPLAY 0.489362 (-4810 5560);
PAINT MONO (-4810 5560);
FORCEPROP 0 LASTPIN (-3450 1100) $PN 44
J 0
(-3440 1110);
DISPLAY 0.489362 (-3440 1110);
PAINT MONO (-3440 1110);
FORCEPROP 0 LASTPIN (-3450 1400) $PN 43
J 0
(-3440 1410);
DISPLAY 0.489362 (-3440 1410);
PAINT MONO (-3440 1410);
FORCEPROP 0 LASTPIN (-4800 750) $PN TH
J 2
(-4810 760);
DISPLAY 0.489362 (-4810 760);
PAINT MONO (-4810 760);
FORCEPROP 0 LASTPIN (-3450 6300) $PN 47
J 0
(-3440 6310);
DISPLAY 0.489362 (-3440 6310);
PAINT MONO (-3440 6310);
FORCEPROP 0 LASTPIN (-3450 6000) $PN 48
J 0
(-3440 6010);
DISPLAY 0.489362 (-3440 6010);
PAINT MONO (-3440 6010);
FORCEPROP 0 LASTPIN (-4800 2050) $PN 19
J 2
(-4810 2060);
DISPLAY 0.489362 (-4810 2060);
PAINT MONO (-4810 2060);
FORCEPROP 0 LASTPIN (-4800 850) $PN 46
J 2
(-4810 860);
DISPLAY 0.489362 (-4810 860);
PAINT MONO (-4810 860);
FORCEPROP 0 LASTPIN (-4800 950) $PN 45
J 2
(-4810 960);
DISPLAY 0.489362 (-4810 960);
PAINT MONO (-4810 960);
FORCEPROP 0 LASTPIN (-4800 4250) $PN 25
J 2
(-4810 4260);
DISPLAY 0.489362 (-4810 4260);
PAINT MONO (-4810 4260);
FORCEPROP 0 LASTPIN (-4800 3150) $PN 40
J 2
(-4810 3160);
DISPLAY 0.489362 (-4810 3160);
PAINT MONO (-4810 3160);
FORCEPROP 2 LAST PART_TYPE SMLF
J 0
(-4300 6475);
DISPLAY 0.638298 (-4300 6475);
FORCEPROP 2 LAST VALUE RAA229620GNP#HA0
J 0
(-4300 6425);
DISPLAY 0.489362 (-4300 6425);
PAINT SKYBLUE (-4300 6425);
FORCEPROP 1 LAST MATERIAL IC
J 0
(-4650 6425);
DISPLAY 0.489362 (-4650 6425);
PAINT SKYBLUE (-4650 6425);
FORCEPROP 1 LAST PART_NUMBER ARF0TGP4002
J 0
(-4650 6500);
DISPLAY 0.489362 (-4650 6500);
PAINT SKYBLUE (-4650 6500);
DISPLAY INVISIBLE (-4650 6500);
FORCEPROP 1 LAST CDS_LMAN_SYM_OUTLINE -550,2850,500,-2850
J 0
(-4100 3550);
DISPLAY 0.468085 (-4100 3550);
PAINT GREEN (-4100 3550);
DISPLAY INVISIBLE (-4100 3550);
FORCEPROP 1 LAST NEEDS_NO_SIZE TRUE
J 0
(-4100 3550);
DISPLAY 0.723404 (-4100 3550);
PAINT GREEN (-4100 3550);
DISPLAY INVISIBLE (-4100 3550);
FORCEPROP 2 LAST CDS_LIB pure_quanta
J 0
(-4100 3550);
DISPLAY INVISIBLE (-4100 3550);
FORCEPROP 1 LAST PATH I128
J 0
(-4100 3550);
DISPLAY 0.723404 (-4100 3550);
PAINT GREEN (-4100 3550);
DISPLAY INVISIBLE (-4100 3550);
FORCEADD Q_RES..2
(-8225 1400);
FORCEPROP 1 LAST LOCATION R6086
J 0
(-8475 1500);
DISPLAY 0.404255 (-8475 1500);
FORCEPROP 0 LAST $SEC 1
J 0
(-8475 1525);
DISPLAY 0.680851 (-8475 1525);
PAINT MONO (-8475 1525);
DISPLAY INVISIBLE (-8475 1525);
FORCEPROP 0 LAST CDS_SEC 1
J 0
(-8475 1525);
DISPLAY 0.680851 (-8475 1525);
DISPLAY INVISIBLE (-8475 1525);
FORCEPROP 1 LASTPIN (-8225 1500) $PN 1
J 0
(-8220 1462);
DISPLAY 0.787234 (-8220 1462);
PAINT MONO (-8220 1462);
FORCEPROP 1 LASTPIN (-8225 1300) $PN 2
J 0
(-8220 1310);
DISPLAY 0.787234 (-8220 1310);
PAINT MONO (-8220 1310);
FORCEPROP 1 LAST VALUE 10K
J 0
(-8475 1450);
DISPLAY 0.404255 (-8475 1450);
FORCEPROP 1 LAST TOLERANCE 1%
J 0
(-8470 1400);
DISPLAY 0.404255 (-8470 1400);
FORCEPROP 1 LAST WATTAGE 1/16W
J 0
(-8475 1350);
DISPLAY 0.404255 (-8475 1350);
FORCEPROP 1 LAST MATERIAL EMPTY
J 0
(-8475 1300);
DISPLAY 0.404255 (-8475 1300);
FORCEPROP 1 LAST PACK_TYPE 0402LF
J 0
(-8475 1200);
DISPLAY 0.404255 (-8475 1200);
FORCEPROP 1 LAST PART_NUMBER CS31002FB08
J 0
(-8475 1250);
DISPLAY 0.404255 (-8475 1250);
DISPLAY INVISIBLE (-8475 1250);
FORCEPROP 2 LAST CDS_LIB pure_quanta
J 0
(-8225 1400);
DISPLAY INVISIBLE (-8225 1400);
FORCEPROP 1 LAST PATH I129
J 0
(-8175 1575);
DISPLAY 0.978723 (-8175 1575);
PAINT WHITE (-8175 1575);
DISPLAY INVISIBLE (-8175 1575);
FORCEADD MOSFET_PCH_GDS_ESD_PROTECTED..1
R 6
(-6975 2075);
FORCEPROP 1 LAST LOCATION PQ10
J 0
(-6800 1925);
DISPLAY 0.489362 (-6800 1925);
PAINT SKYBLUE (-6800 1925);
FORCEPROP 0 LAST $SEC 1
J 0
(-6800 2100);
DISPLAY 0.680851 (-6800 2100);
PAINT MONO (-6800 2100);
DISPLAY INVISIBLE (-6800 2100);
FORCEPROP 0 LAST CDS_SEC 1
J 0
(-6800 2100);
DISPLAY 1.021277 (-6800 2100);
DISPLAY INVISIBLE (-6800 2100);
FORCEPROP 0 LASTPIN (-6950 1775) $PN D
R 1
J 2
(-6960 1765);
DISPLAY 0.489362 (-6960 1765);
PAINT MONO (-6960 1765);
FORCEPROP 0 LASTPIN (-7250 2075) $PN G
J 2
(-7260 2085);
DISPLAY 0.489362 (-7260 2085);
PAINT MONO (-7260 2085);
FORCEPROP 0 LASTPIN (-6950 2375) $PN S
R 1
J 0
(-6960 2385);
DISPLAY 0.489362 (-6960 2385);
PAINT MONO (-6960 2385);
FORCEPROP 2 LAST VALUE PJA3415AE
J 0
(-6800 2027);
DISPLAY 0.489362 (-6800 2027);
PAINT SKYBLUE (-6800 2027);
FORCEPROP 1 LAST MATERIAL IC
J 0
(-6800 2077);
DISPLAY 0.489362 (-6800 2077);
PAINT SKYBLUE (-6800 2077);
FORCEPROP 1 LAST PART_NUMBER BAM34150008
J 0
(-6800 1977);
DISPLAY 0.489362 (-6800 1977);
PAINT SKYBLUE (-6800 1977);
DISPLAY INVISIBLE (-6800 1977);
FORCEPROP 2 LAST PART_TYPE SMLF
J 0
(-6825 1902);
DISPLAY 1.021277 (-6825 1902);
DISPLAY INVISIBLE (-6825 1902);
FORCEPROP 2 LAST CDS_LIB pure_quanta
J 0
(-6975 2075);
DISPLAY INVISIBLE (-6975 2075);
FORCEPROP 1 LAST NEEDS_NO_SIZE TRUE
J 0
(-6975 2041);
DISPLAY 0.723404 (-6975 2041);
PAINT GREEN (-6975 2041);
DISPLAY INVISIBLE (-6975 2041);
FORCEPROP 1 LAST CDS_LMAN_SYM_OUTLINE -125,150,125,-150
J 0
(-6975 2075);
DISPLAY 0.468085 (-6975 2075);
PAINT GREEN (-6975 2075);
DISPLAY INVISIBLE (-6975 2075);
FORCEPROP 1 LAST PATH I13
J 0
(-6975 2075);
DISPLAY 0.723404 (-6975 2075);
PAINT GREEN (-6975 2075);
DISPLAY INVISIBLE (-6975 2075);
FORCEADD Q_CAP..1
(-6100 4675);
FORCEPROP 1 LAST LOCATION C5013
J 0
(-6000 4675);
DISPLAY 0.510638 (-6000 4675);
FORCEPROP 0 LAST $SEC 1
J 0
(-5850 4700);
DISPLAY 0.680851 (-5850 4700);
PAINT MONO (-5850 4700);
DISPLAY INVISIBLE (-5850 4700);
FORCEPROP 0 LAST CDS_SEC 1
J 0
(-5850 4700);
DISPLAY 0.680851 (-5850 4700);
DISPLAY INVISIBLE (-5850 4700);
FORCEPROP 1 LASTPIN (-6100 4775) $PN 1
J 0
(-6090 4755);
DISPLAY 0.787234 (-6090 4755);
PAINT MONO (-6090 4755);
FORCEPROP 1 LASTPIN (-6100 4575) $PN 2
J 0
(-6090 4555);
DISPLAY 0.787234 (-6090 4555);
PAINT MONO (-6090 4555);
FORCEPROP 1 LAST VALUE 1000PF
J 0
(-6025 4650);
DISPLAY 0.510638 (-6025 4650);
FORCEPROP 1 LAST TOLERANCE 5%
J 0
(-5850 4575);
DISPLAY 0.510638 (-5850 4575);
FORCEPROP 1 LAST PACK_TYPE 0402
J 0
(-5850 4650);
DISPLAY 0.510638 (-5850 4650);
FORCEPROP 1 LAST VOLTAGE 50V
J 0
(-5850 4600);
DISPLAY 0.510638 (-5850 4600);
FORCEPROP 1 LAST MATERIAL X7R
J 0
(-5850 4625);
DISPLAY 0.510638 (-5850 4625);
FORCEPROP 1 LAST PART_NUMBER TMP_QCH21006JB10
J 0
(-5850 4675);
DISPLAY 0.510638 (-5850 4675);
DISPLAY INVISIBLE (-5850 4675);
FORCEPROP 2 LAST CDS_LIB pure_quanta
J 0
(-6100 4675);
DISPLAY INVISIBLE (-6100 4675);
FORCEPROP 1 LAST PATH I130
J 0
(-6050 4825);
DISPLAY 0.978723 (-6050 4825);
PAINT WHITE (-6050 4825);
DISPLAY INVISIBLE (-6050 4825);
FORCEADD UNIVERSAL_GND..1
(-6100 4475);
FORCEPROP 3 LASTPIN (-6100 4525) SIG_NAME GND\g
J 0
(-6090 4535);
DISPLAY 0.659574 (-6090 4535);
PAINT MONO (-6090 4535);
DISPLAY INVISIBLE (-6090 4535);
FORCEPROP 1 LAST HDL_POWER GND
J 1
(-6075 4400);
DISPLAY 0.872340 (-6075 4400);
PAINT GREEN (-6075 4400);
DISPLAY INVISIBLE (-6075 4400);
FORCEPROP 2 LAST CDS_LIB pure_quanta_power
J 0
(-6100 4475);
PAINT MONO (-6100 4475);
DISPLAY INVISIBLE (-6100 4475);
FORCEPROP 1 LAST PATH I131
J 0
(-6025 4475);
DISPLAY 0.872340 (-6025 4475);
PAINT AQUA (-6025 4475);
DISPLAY INVISIBLE (-6025 4475);
FORCEADD UNIVERSAL_GND..1
R 7
(-7575 1175);
FORCEPROP 3 LASTPIN (-7525 1175) SIG_NAME GND\g
J 0
(-7515 1185);
DISPLAY 0.659574 (-7515 1185);
PAINT MONO (-7515 1185);
DISPLAY INVISIBLE (-7515 1185);
FORCEPROP 1 LAST HDL_POWER GND
R 1
J 1
(-7650 1200);
DISPLAY 0.872340 (-7650 1200);
PAINT GREEN (-7650 1200);
DISPLAY INVISIBLE (-7650 1200);
FORCEPROP 2 LAST CDS_LIB pure_quanta_power
R 1
J 0
(-7575 1175);
DISPLAY INVISIBLE (-7575 1175);
FORCEPROP 1 LAST PATH I132
R 1
J 0
(-7575 1250);
DISPLAY 0.872340 (-7575 1250);
PAINT AQUA (-7575 1250);
DISPLAY INVISIBLE (-7575 1250);
FORCEADD Q_CAP..2
(-7275 1175);
FORCEPROP 1 LAST LOCATION C5005
J 1
(-7450 1175);
DISPLAY 0.489362 (-7450 1175);
PAINT SKYBLUE (-7450 1175);
FORCEPROP 0 LAST $SEC 1
J 0
(-7325 1275);
DISPLAY 0.680851 (-7325 1275);
PAINT MONO (-7325 1275);
DISPLAY INVISIBLE (-7325 1275);
FORCEPROP 0 LAST CDS_SEC 1
J 0
(-7325 1275);
DISPLAY 1.021277 (-7325 1275);
DISPLAY INVISIBLE (-7325 1275);
FORCEPROP 1 LASTPIN (-7375 1175) $PN 1
J 0
(-7385 1190);
DISPLAY 0.489362 (-7385 1190);
PAINT MONO (-7385 1190);
FORCEPROP 1 LASTPIN (-7175 1175) $PN 2
J 0
(-7190 1190);
DISPLAY 0.489362 (-7190 1190);
PAINT MONO (-7190 1190);
FORCEPROP 1 LAST VOLTAGE 50V
J 0
(-7400 1250);
DISPLAY 0.489362 (-7400 1250);
PAINT SKYBLUE (-7400 1250);
FORCEPROP 1 LAST TOLERANCE 5%
J 2
(-7450 1250);
DISPLAY 0.489362 (-7450 1250);
PAINT SKYBLUE (-7450 1250);
FORCEPROP 1 LAST PACK_TYPE 0402
J 1
(-7375 1225);
DISPLAY 0.489362 (-7375 1225);
PAINT SKYBLUE (-7375 1225);
FORCEPROP 1 LAST MATERIAL X7R
J 0
(-7525 1225);
DISPLAY 0.489362 (-7525 1225);
PAINT SKYBLUE (-7525 1225);
FORCEPROP 1 LAST VALUE 1000PF
J 2
(-7000 1175);
DISPLAY 0.489362 (-7000 1175);
PAINT SKYBLUE (-7000 1175);
FORCEPROP 1 LAST PART_NUMBER TMP_QCH21006JB10
J 1
(-7375 1300);
DISPLAY 0.489362 (-7375 1300);
PAINT SKYBLUE (-7375 1300);
DISPLAY INVISIBLE (-7375 1300);
FORCEPROP 2 LAST CDS_LIB pure_quanta
J 0
(-7275 1175);
DISPLAY INVISIBLE (-7275 1175);
FORCEPROP 1 LAST PATH I133
J 0
(-7275 1375);
DISPLAY 0.978723 (-7275 1375);
PAINT WHITE (-7275 1375);
DISPLAY INVISIBLE (-7275 1375);
FORCEADD UNIVERSAL_GND..1
R 7
(-7550 6375);
FORCEPROP 3 LASTPIN (-7500 6375) SIG_NAME GND\g
J 0
(-7490 6385);
DISPLAY 0.659574 (-7490 6385);
PAINT MONO (-7490 6385);
DISPLAY INVISIBLE (-7490 6385);
FORCEPROP 1 LAST HDL_POWER GND
R 1
J 1
(-7625 6400);
DISPLAY 0.872340 (-7625 6400);
PAINT GREEN (-7625 6400);
DISPLAY INVISIBLE (-7625 6400);
FORCEPROP 2 LAST CDS_LIB pure_quanta_power
R 1
J 0
(-7550 6375);
DISPLAY INVISIBLE (-7550 6375);
FORCEPROP 1 LAST PATH I134
R 1
J 0
(-7550 6450);
DISPLAY 0.872340 (-7550 6450);
PAINT AQUA (-7550 6450);
DISPLAY INVISIBLE (-7550 6450);
FORCEADD Q_CAP..2
(-7250 6375);
FORCEPROP 1 LAST LOCATION C5004
J 1
(-7425 6375);
DISPLAY 0.489362 (-7425 6375);
PAINT SKYBLUE (-7425 6375);
FORCEPROP 0 LAST $SEC 1
J 0
(-7300 6475);
DISPLAY 0.680851 (-7300 6475);
PAINT MONO (-7300 6475);
DISPLAY INVISIBLE (-7300 6475);
FORCEPROP 0 LAST CDS_SEC 1
J 0
(-7300 6475);
DISPLAY 1.021277 (-7300 6475);
DISPLAY INVISIBLE (-7300 6475);
FORCEPROP 1 LASTPIN (-7350 6375) $PN 1
J 0
(-7360 6390);
DISPLAY 0.489362 (-7360 6390);
PAINT MONO (-7360 6390);
FORCEPROP 1 LASTPIN (-7150 6375) $PN 2
J 0
(-7165 6390);
DISPLAY 0.489362 (-7165 6390);
PAINT MONO (-7165 6390);
FORCEPROP 1 LAST TOLERANCE 5%
J 2
(-7425 6450);
DISPLAY 0.489362 (-7425 6450);
PAINT SKYBLUE (-7425 6450);
FORCEPROP 1 LAST PACK_TYPE 0402
J 1
(-7350 6425);
DISPLAY 0.489362 (-7350 6425);
PAINT SKYBLUE (-7350 6425);
FORCEPROP 1 LAST VOLTAGE 50V
J 0
(-7375 6450);
DISPLAY 0.489362 (-7375 6450);
PAINT SKYBLUE (-7375 6450);
FORCEPROP 1 LAST MATERIAL X7R
J 0
(-7500 6425);
DISPLAY 0.489362 (-7500 6425);
PAINT SKYBLUE (-7500 6425);
FORCEPROP 1 LAST VALUE 1000PF
J 2
(-6975 6375);
DISPLAY 0.489362 (-6975 6375);
PAINT SKYBLUE (-6975 6375);
FORCEPROP 1 LAST PART_NUMBER TMP_QCH21006JB10
J 1
(-7350 6500);
DISPLAY 0.489362 (-7350 6500);
PAINT SKYBLUE (-7350 6500);
DISPLAY INVISIBLE (-7350 6500);
FORCEPROP 2 LAST CDS_LIB pure_quanta
J 0
(-7250 6375);
DISPLAY INVISIBLE (-7250 6375);
FORCEPROP 1 LAST PATH I135
J 0
(-7250 6575);
DISPLAY 0.978723 (-7250 6575);
PAINT WHITE (-7250 6575);
DISPLAY INVISIBLE (-7250 6575);
FORCEADD Q_RES..1
(-6500 5700);
FORCEPROP 1 LAST LOCATION PR8008
J 0
(-6550 5750);
DISPLAY 0.489362 (-6550 5750);
PAINT SKYBLUE (-6550 5750);
FORCEPROP 0 LAST $SEC 1
J 0
(-6100 5825);
DISPLAY 0.680851 (-6100 5825);
PAINT MONO (-6100 5825);
DISPLAY INVISIBLE (-6100 5825);
FORCEPROP 0 LAST CDS_SEC 1
J 0
(-6100 5825);
DISPLAY 0.680851 (-6100 5825);
DISPLAY INVISIBLE (-6100 5825);
FORCEPROP 1 LASTPIN (-6600 5700) $PN 1
J 0
(-6588 5712);
DISPLAY 0.787234 (-6588 5712);
PAINT MONO (-6588 5712);
FORCEPROP 1 LASTPIN (-6400 5700) $PN 2
J 0
(-6438 5712);
DISPLAY 0.787234 (-6438 5712);
PAINT MONO (-6438 5712);
FORCEPROP 1 LAST PACK_TYPE 0402LF
J 0
(-5875 5750);
DISPLAY 0.489362 (-5875 5750);
PAINT SKYBLUE (-5875 5750);
FORCEPROP 1 LAST VALUE 0
J 2
(-5975 5750);
DISPLAY 0.489362 (-5975 5750);
PAINT SKYBLUE (-5975 5750);
FORCEPROP 1 LAST MATERIAL CHIP
J 0
(-6375 5800);
DISPLAY 0.489362 (-6375 5800);
PAINT SKYBLUE (-6375 5800);
FORCEPROP 1 LAST WATTAGE 1/16W
J 2
(-6100 5800);
DISPLAY 0.489362 (-6100 5800);
PAINT SKYBLUE (-6100 5800);
FORCEPROP 1 LAST TOLERANCE 5%
J 0
(-5950 5750);
DISPLAY 0.489362 (-5950 5750);
PAINT SKYBLUE (-5950 5750);
FORCEPROP 1 LAST PART_NUMBER CS00002JB13
J 0
(-6375 5750);
DISPLAY 0.489362 (-6375 5750);
PAINT SKYBLUE (-6375 5750);
DISPLAY INVISIBLE (-6375 5750);
FORCEPROP 2 LAST CDS_LIB pure_quanta
J 0
(-6500 5700);
DISPLAY INVISIBLE (-6500 5700);
FORCEPROP 1 LAST PATH I136
J 0
(-6550 5850);
DISPLAY 0.978723 (-6550 5850);
PAINT WHITE (-6550 5850);
DISPLAY INVISIBLE (-6550 5850);
FORCEADD Q_RES..1
(-6475 5850);
FORCEPROP 1 LAST LOCATION PR8007
J 0
(-6525 5900);
DISPLAY 0.489362 (-6525 5900);
PAINT SKYBLUE (-6525 5900);
FORCEPROP 0 LAST $SEC 1
J 0
(-6075 5975);
DISPLAY 0.680851 (-6075 5975);
PAINT MONO (-6075 5975);
DISPLAY INVISIBLE (-6075 5975);
FORCEPROP 0 LAST CDS_SEC 1
J 0
(-6075 5975);
DISPLAY 0.680851 (-6075 5975);
DISPLAY INVISIBLE (-6075 5975);
FORCEPROP 1 LASTPIN (-6575 5850) $PN 1
J 0
(-6563 5862);
DISPLAY 0.787234 (-6563 5862);
PAINT MONO (-6563 5862);
FORCEPROP 1 LASTPIN (-6375 5850) $PN 2
J 0
(-6413 5862);
DISPLAY 0.787234 (-6413 5862);
PAINT MONO (-6413 5862);
FORCEPROP 1 LAST PACK_TYPE 0402LF
J 0
(-5850 5900);
DISPLAY 0.489362 (-5850 5900);
PAINT SKYBLUE (-5850 5900);
FORCEPROP 1 LAST WATTAGE 1/16W
J 2
(-6075 5950);
DISPLAY 0.489362 (-6075 5950);
PAINT SKYBLUE (-6075 5950);
FORCEPROP 1 LAST VALUE 0
J 2
(-5950 5900);
DISPLAY 0.489362 (-5950 5900);
PAINT SKYBLUE (-5950 5900);
FORCEPROP 1 LAST MATERIAL CHIP
J 0
(-6350 5950);
DISPLAY 0.489362 (-6350 5950);
PAINT SKYBLUE (-6350 5950);
FORCEPROP 1 LAST TOLERANCE 5%
J 0
(-5925 5900);
DISPLAY 0.489362 (-5925 5900);
PAINT SKYBLUE (-5925 5900);
FORCEPROP 1 LAST PART_NUMBER CS00002JB13
J 0
(-6350 5900);
DISPLAY 0.489362 (-6350 5900);
PAINT SKYBLUE (-6350 5900);
DISPLAY INVISIBLE (-6350 5900);
FORCEPROP 2 LAST CDS_LIB pure_quanta
J 0
(-6475 5850);
DISPLAY INVISIBLE (-6475 5850);
FORCEPROP 1 LAST PATH I137
J 0
(-6525 6000);
DISPLAY 0.978723 (-6525 6000);
PAINT WHITE (-6525 6000);
DISPLAY INVISIBLE (-6525 6000);
FORCEADD OFFPAGE..1
(-8350 2825);
FORCEPROP 2 LAST $XR0 27 
J 0
(-8661 2825);
DISPLAY 0.638298 (-8661 2825);
PAINT MONO (-8661 2825);
FORCEPROP 1 LAST COMMENT_BODY TRUE
J 0
(-8225 2725);
DISPLAY 0.872340 (-8225 2725);
PAINT GREEN (-8225 2725);
DISPLAY INVISIBLE (-8225 2725);
FORCEPROP 1 LAST OFFPAGE TRUE
J 0
(-8025 2700);
DISPLAY 0.872340 (-8025 2700);
PAINT GREEN (-8025 2700);
DISPLAY INVISIBLE (-8025 2700);
FORCEPROP 2 LAST CDS_LIB standard
J 0
(-8350 2825);
DISPLAY INVISIBLE (-8350 2825);
FORCEPROP 2 LAST PATH I14
J 0
(-8650 2875);
DISPLAY 0.680851 (-8650 2875);
DISPLAY INVISIBLE (-8650 2875);
FORCEADD OFFPAGE..1
(-8350 3200);
FORCEPROP 2 LAST $XR0 27 
J 0
(-8661 3200);
DISPLAY 0.638298 (-8661 3200);
PAINT MONO (-8661 3200);
FORCEPROP 1 LAST COMMENT_BODY TRUE
J 0
(-8225 3100);
DISPLAY 0.872340 (-8225 3100);
PAINT GREEN (-8225 3100);
DISPLAY INVISIBLE (-8225 3100);
FORCEPROP 1 LAST OFFPAGE TRUE
J 0
(-8025 3075);
DISPLAY 0.872340 (-8025 3075);
PAINT GREEN (-8025 3075);
DISPLAY INVISIBLE (-8025 3075);
FORCEPROP 2 LAST CDS_LIB standard
J 0
(-8350 3200);
DISPLAY INVISIBLE (-8350 3200);
FORCEPROP 2 LAST PATH I15
J 0
(-8650 3250);
DISPLAY 0.680851 (-8650 3250);
DISPLAY INVISIBLE (-8650 3250);
FORCEADD OFFPAGE..1
(-8350 3925);
FORCEPROP 2 LAST $XR0 27 
J 0
(-8631 3925);
DISPLAY 0.638298 (-8631 3925);
PAINT MONO (-8631 3925);
FORCEPROP 2 LAST $XR1 207 
J 0
(-8751 3925);
DISPLAY 0.638298 (-8751 3925);
PAINT MONO (-8751 3925);
FORCEPROP 1 LAST COMMENT_BODY TRUE
J 0
(-8225 3825);
DISPLAY 0.872340 (-8225 3825);
PAINT GREEN (-8225 3825);
DISPLAY INVISIBLE (-8225 3825);
FORCEPROP 1 LAST OFFPAGE TRUE
J 0
(-8025 3800);
DISPLAY 0.872340 (-8025 3800);
PAINT GREEN (-8025 3800);
DISPLAY INVISIBLE (-8025 3800);
FORCEPROP 2 LAST CDS_LIB standard
J 0
(-8350 3925);
DISPLAY INVISIBLE (-8350 3925);
FORCEPROP 2 LAST PATH I16
J 0
(-8625 3975);
DISPLAY 0.680851 (-8625 3975);
DISPLAY INVISIBLE (-8625 3975);
FORCEADD Q_RES..2
(-7600 2275);
FORCEPROP 1 LAST LOCATION PR55
J 0
(-7550 2400);
DISPLAY 0.489362 (-7550 2400);
PAINT SKYBLUE (-7550 2400);
FORCEPROP 0 LAST $SEC 1
J 0
(-7550 2425);
DISPLAY 0.680851 (-7550 2425);
PAINT MONO (-7550 2425);
DISPLAY INVISIBLE (-7550 2425);
FORCEPROP 0 LAST CDS_SEC 1
J 0
(-7850 2375);
DISPLAY 1.021277 (-7850 2375);
DISPLAY INVISIBLE (-7850 2375);
FORCEPROP 1 LASTPIN (-7600 2375) $PN 1
J 0
(-7595 2337);
DISPLAY 0.489362 (-7595 2337);
PAINT MONO (-7595 2337);
FORCEPROP 1 LASTPIN (-7600 2175) $PN 2
J 0
(-7595 2185);
DISPLAY 0.489362 (-7595 2185);
PAINT MONO (-7595 2185);
FORCEPROP 1 LAST VALUE 1K
J 0
(-7550 2350);
DISPLAY 0.489362 (-7550 2350);
PAINT SKYBLUE (-7550 2350);
FORCEPROP 1 LAST PACK_TYPE 0402LF
J 0
(-7550 2150);
DISPLAY 0.489362 (-7550 2150);
PAINT SKYBLUE (-7550 2150);
FORCEPROP 1 LAST TOLERANCE 1%
J 0
(-7550 2300);
DISPLAY 0.489362 (-7550 2300);
PAINT SKYBLUE (-7550 2300);
FORCEPROP 1 LAST WATTAGE 1/16W
J 0
(-7550 2250);
DISPLAY 0.489362 (-7550 2250);
PAINT SKYBLUE (-7550 2250);
FORCEPROP 1 LAST MATERIAL CHIP
J 0
(-7550 2200);
DISPLAY 0.489362 (-7550 2200);
PAINT SKYBLUE (-7550 2200);
FORCEPROP 1 LAST PART_NUMBER CS21002FB06
J 0
(-7560 2150);
DISPLAY 0.489362 (-7560 2150);
PAINT SKYBLUE (-7560 2150);
DISPLAY INVISIBLE (-7560 2150);
FORCEPROP 2 LAST CDS_LIB pure_quanta
J 0
(-7600 2275);
DISPLAY INVISIBLE (-7600 2275);
FORCEPROP 1 LAST PATH I17
J 0
(-7550 2450);
DISPLAY 0.978723 (-7550 2450);
PAINT WHITE (-7550 2450);
DISPLAY INVISIBLE (-7550 2450);
FORCEADD VCC_CORE..1
(-7600 2575);
FORCEPROP 3 LASTPIN (-7600 2525) SIG_NAME P3V3_AUX\g
J 0
(-7590 2535);
DISPLAY 0.659574 (-7590 2535);
PAINT MONO (-7590 2535);
DISPLAY INVISIBLE (-7590 2535);
FORCEPROP 1 LAST HDL_POWER P3V3_AUX
J 1
(-7600 2625);
DISPLAY 0.489362 (-7600 2625);
PAINT GREEN (-7600 2625);
FORCEPROP 2 LAST CDS_LIB pure_quanta_power
J 0
(-7600 2575);
DISPLAY INVISIBLE (-7600 2575);
FORCEPROP 1 LAST PATH I18
J 0
(-7550 2600);
DISPLAY 0.872340 (-7550 2600);
PAINT AQUA (-7550 2600);
DISPLAY INVISIBLE (-7550 2600);
FORCEADD Q_RES..1
(-7150 2675);
FORCEPROP 1 LAST LOCATION PR50
J 0
(-7350 2675);
DISPLAY 0.489362 (-7350 2675);
PAINT SKYBLUE (-7350 2675);
FORCEPROP 2 LAST $SEC 1
J 0
(-7200 2875);
DISPLAY 0.680851 (-7200 2875);
PAINT MONO (-7200 2875);
DISPLAY INVISIBLE (-7200 2875);
FORCEPROP 2 LAST CDS_SEC 1
J 0
(-7200 2875);
DISPLAY 1.021277 (-7200 2875);
DISPLAY INVISIBLE (-7200 2875);
FORCEPROP 1 LASTPIN (-7250 2675) $PN 1
J 0
(-7238 2687);
DISPLAY 0.489362 (-7238 2687);
FORCEPROP 1 LASTPIN (-7050 2675) $PN 2
J 0
(-7088 2687);
DISPLAY 0.489362 (-7088 2687);
FORCEPROP 1 LAST WATTAGE 1/16W
J 2
(-6775 2775);
DISPLAY 0.489362 (-6775 2775);
PAINT SKYBLUE (-6775 2775);
FORCEPROP 1 LAST PACK_TYPE 0402LF
J 0
(-6850 2675);
DISPLAY 0.489362 (-6850 2675);
PAINT SKYBLUE (-6850 2675);
FORCEPROP 1 LAST MATERIAL CHIP
J 0
(-7025 2775);
DISPLAY 0.489362 (-7025 2775);
PAINT SKYBLUE (-7025 2775);
FORCEPROP 1 LAST VALUE 49.9
J 2
(-6975 2725);
DISPLAY 0.489362 (-6975 2725);
PAINT SKYBLUE (-6975 2725);
FORCEPROP 1 LAST TOLERANCE 1%
J 0
(-6925 2675);
DISPLAY 0.489362 (-6925 2675);
PAINT SKYBLUE (-6925 2675);
FORCEPROP 1 LAST PART_NUMBER CS04992FB07
J 0
(-7025 2725);
DISPLAY 0.489362 (-7025 2725);
PAINT SKYBLUE (-7025 2725);
DISPLAY INVISIBLE (-7025 2725);
FORCEPROP 2 LAST CDS_LIB pure_quanta
J 0
(-7150 2675);
PAINT MONO (-7150 2675);
DISPLAY INVISIBLE (-7150 2675);
FORCEPROP 1 LAST PATH I19
J 0
(-7200 2825);
DISPLAY 0.978723 (-7200 2825);
PAINT WHITE (-7200 2825);
DISPLAY INVISIBLE (-7200 2825);
FORCEADD Q_RES..1
(-8350 1650);
FORCEPROP 1 LAST LOCATION R8047
J 0
(-8325 1700);
DISPLAY 0.489362 (-8325 1700);
PAINT SKYBLUE (-8325 1700);
FORCEPROP 0 LAST $SEC 1
J 0
(-8000 1800);
DISPLAY 0.680851 (-8000 1800);
PAINT MONO (-8000 1800);
DISPLAY INVISIBLE (-8000 1800);
FORCEPROP 0 LAST CDS_SEC 1
J 0
(-8000 1800);
DISPLAY 1.021277 (-8000 1800);
DISPLAY INVISIBLE (-8000 1800);
FORCEPROP 1 LASTPIN (-8450 1650) $PN 1
J 0
(-8438 1662);
DISPLAY 0.489362 (-8438 1662);
PAINT MONO (-8438 1662);
FORCEPROP 1 LASTPIN (-8250 1650) $PN 2
J 0
(-8288 1662);
DISPLAY 0.489362 (-8288 1662);
PAINT MONO (-8288 1662);
FORCEPROP 1 LAST TOLERANCE 5%
J 0
(-8450 1750);
DISPLAY 0.489362 (-8450 1750);
PAINT SKYBLUE (-8450 1750);
FORCEPROP 1 LAST VALUE 0
J 2
(-8425 1700);
DISPLAY 0.489362 (-8425 1700);
PAINT SKYBLUE (-8425 1700);
FORCEPROP 1 LAST MATERIAL CHIP
J 0
(-8500 1850);
DISPLAY 0.489362 (-8500 1850);
PAINT SKYBLUE (-8500 1850);
FORCEPROP 1 LAST PACK_TYPE 0402LF
J 0
(-8375 1750);
DISPLAY 0.489362 (-8375 1750);
PAINT SKYBLUE (-8375 1750);
FORCEPROP 1 LAST WATTAGE 1/16W
J 2
(-8250 1850);
DISPLAY 0.489362 (-8250 1850);
PAINT SKYBLUE (-8250 1850);
FORCEPROP 1 LAST PART_NUMBER CS00002JB13
J 0
(-8500 1800);
DISPLAY 0.489362 (-8500 1800);
PAINT SKYBLUE (-8500 1800);
DISPLAY INVISIBLE (-8500 1800);
FORCEPROP 1 LAST PATH I2
J 0
(-8400 1800);
DISPLAY 0.978723 (-8400 1800);
PAINT WHITE (-8400 1800);
DISPLAY INVISIBLE (-8400 1800);
FORCEPROP 2 LAST CDS_LIB pure_quanta
J 0
(-8350 1650);
DISPLAY INVISIBLE (-8350 1650);
FORCEADD OFFPAGE..1
(-6450 2450);
FORCEPROP 2 LAST $XR0 78 
J 0
(-6701 2450);
DISPLAY 0.638298 (-6701 2450);
PAINT MONO (-6701 2450);
FORCEPROP 2 LAST PATH I20
J 0
(-6650 2500);
DISPLAY 0.680851 (-6650 2500);
DISPLAY INVISIBLE (-6650 2500);
FORCEPROP 1 LAST COMMENT_BODY TRUE
J 0
(-6325 2350);
DISPLAY 0.872340 (-6325 2350);
PAINT GREEN (-6325 2350);
DISPLAY INVISIBLE (-6325 2350);
FORCEPROP 1 LAST OFFPAGE TRUE
J 0
(-6125 2325);
DISPLAY 0.872340 (-6125 2325);
PAINT GREEN (-6125 2325);
DISPLAY INVISIBLE (-6125 2325);
FORCEPROP 2 LAST CDS_LIB standard
J 0
(-6450 2450);
DISPLAY INVISIBLE (-6450 2450);
FORCEADD UNIVERSAL_GND..1
(-6625 2575);
FORCEPROP 3 LASTPIN (-6625 2625) SIG_NAME GND\g
J 0
(-6615 2635);
DISPLAY 0.659574 (-6615 2635);
PAINT MONO (-6615 2635);
DISPLAY INVISIBLE (-6615 2635);
FORCEPROP 1 LAST HDL_POWER GND
J 1
(-6600 2500);
DISPLAY 0.872340 (-6600 2500);
PAINT GREEN (-6600 2500);
DISPLAY INVISIBLE (-6600 2500);
FORCEPROP 2 LAST CDS_LIB pure_quanta_power
J 0
(-6625 2575);
PAINT MONO (-6625 2575);
DISPLAY INVISIBLE (-6625 2575);
FORCEPROP 1 LAST PATH I21
J 0
(-6550 2575);
DISPLAY 0.872340 (-6550 2575);
PAINT AQUA (-6550 2575);
DISPLAY INVISIBLE (-6550 2575);
FORCEADD Q_RES..1
(-7100 3350);
FORCEPROP 1 LAST LOCATION PR52
J 0
(-7300 3350);
DISPLAY 0.489362 (-7300 3350);
PAINT SKYBLUE (-7300 3350);
FORCEPROP 2 LAST $SEC 1
J 0
(-7150 3550);
DISPLAY 0.680851 (-7150 3550);
PAINT MONO (-7150 3550);
DISPLAY INVISIBLE (-7150 3550);
FORCEPROP 2 LAST CDS_SEC 1
J 0
(-7150 3550);
DISPLAY 1.021277 (-7150 3550);
DISPLAY INVISIBLE (-7150 3550);
FORCEPROP 1 LASTPIN (-7200 3350) $PN 1
J 0
(-7188 3362);
DISPLAY 0.489362 (-7188 3362);
FORCEPROP 1 LASTPIN (-7000 3350) $PN 2
J 0
(-7038 3362);
DISPLAY 0.489362 (-7038 3362);
FORCEPROP 1 LAST TOLERANCE 1%
J 0
(-6875 3350);
DISPLAY 0.489362 (-6875 3350);
PAINT SKYBLUE (-6875 3350);
FORCEPROP 1 LAST VALUE 49.9
J 2
(-6925 3400);
DISPLAY 0.489362 (-6925 3400);
PAINT SKYBLUE (-6925 3400);
FORCEPROP 1 LAST PACK_TYPE 0402LF
J 0
(-6800 3350);
DISPLAY 0.489362 (-6800 3350);
PAINT SKYBLUE (-6800 3350);
FORCEPROP 1 LAST MATERIAL CHIP
J 0
(-6975 3450);
DISPLAY 0.489362 (-6975 3450);
PAINT SKYBLUE (-6975 3450);
FORCEPROP 1 LAST WATTAGE 1/16W
J 2
(-6725 3450);
DISPLAY 0.489362 (-6725 3450);
PAINT SKYBLUE (-6725 3450);
FORCEPROP 1 LAST PART_NUMBER CS04992FB07
J 0
(-6975 3400);
DISPLAY 0.489362 (-6975 3400);
PAINT SKYBLUE (-6975 3400);
DISPLAY INVISIBLE (-6975 3400);
FORCEPROP 1 LAST PATH I22
J 0
(-7150 3500);
DISPLAY 0.978723 (-7150 3500);
PAINT WHITE (-7150 3500);
DISPLAY INVISIBLE (-7150 3500);
FORCEPROP 2 LAST CDS_LIB pure_quanta
J 0
(-7100 3350);
PAINT MONO (-7100 3350);
DISPLAY INVISIBLE (-7100 3350);
FORCEADD Q_RES..1
(-7150 3775);
FORCEPROP 1 LAST LOCATION PR49
J 0
(-7350 3775);
DISPLAY 0.489362 (-7350 3775);
PAINT SKYBLUE (-7350 3775);
FORCEPROP 2 LAST $SEC 1
J 0
(-7200 3975);
DISPLAY 0.680851 (-7200 3975);
PAINT MONO (-7200 3975);
DISPLAY INVISIBLE (-7200 3975);
FORCEPROP 2 LAST CDS_SEC 1
J 0
(-7200 3975);
DISPLAY 1.021277 (-7200 3975);
DISPLAY INVISIBLE (-7200 3975);
FORCEPROP 1 LASTPIN (-7250 3775) $PN 1
J 0
(-7238 3787);
DISPLAY 0.489362 (-7238 3787);
FORCEPROP 1 LASTPIN (-7050 3775) $PN 2
J 0
(-7088 3787);
DISPLAY 0.489362 (-7088 3787);
FORCEPROP 1 LAST TOLERANCE 1%
J 0
(-6925 3775);
DISPLAY 0.489362 (-6925 3775);
PAINT SKYBLUE (-6925 3775);
FORCEPROP 1 LAST PACK_TYPE 0402LF
J 0
(-6850 3775);
DISPLAY 0.489362 (-6850 3775);
PAINT SKYBLUE (-6850 3775);
FORCEPROP 1 LAST MATERIAL CHIP
J 0
(-7025 3875);
DISPLAY 0.489362 (-7025 3875);
PAINT SKYBLUE (-7025 3875);
FORCEPROP 1 LAST WATTAGE 1/16W
J 2
(-6775 3875);
DISPLAY 0.489362 (-6775 3875);
PAINT SKYBLUE (-6775 3875);
FORCEPROP 1 LAST VALUE 49.9
J 2
(-6975 3825);
DISPLAY 0.489362 (-6975 3825);
PAINT SKYBLUE (-6975 3825);
FORCEPROP 1 LAST PART_NUMBER CS04992FB07
J 0
(-7025 3825);
DISPLAY 0.489362 (-7025 3825);
PAINT SKYBLUE (-7025 3825);
DISPLAY INVISIBLE (-7025 3825);
FORCEPROP 1 LAST PATH I23
J 0
(-7200 3925);
DISPLAY 0.978723 (-7200 3925);
PAINT WHITE (-7200 3925);
DISPLAY INVISIBLE (-7200 3925);
FORCEPROP 2 LAST CDS_LIB pure_quanta
J 0
(-7150 3775);
PAINT MONO (-7150 3775);
DISPLAY INVISIBLE (-7150 3775);
FORCEADD VCC_CORE..1
(-6600 3500);
FORCEPROP 3 LASTPIN (-6600 3450) SIG_NAME PVDDIO_P0\g
J 0
(-6590 3460);
DISPLAY 0.659574 (-6590 3460);
PAINT MONO (-6590 3460);
DISPLAY INVISIBLE (-6590 3460);
FORCEPROP 1 LAST HDL_POWER PVDDIO_P0
J 1
(-6600 3550);
DISPLAY 0.489362 (-6600 3550);
PAINT GREEN (-6600 3550);
FORCEPROP 1 LAST PATH I24
J 0
(-6550 3525);
DISPLAY 0.872340 (-6550 3525);
PAINT AQUA (-6550 3525);
DISPLAY INVISIBLE (-6550 3525);
FORCEPROP 2 LAST CDS_LIB pure_quanta_power
J 0
(-6600 3500);
DISPLAY INVISIBLE (-6600 3500);
FORCEADD UNIVERSAL_GND..1
(-6625 3675);
FORCEPROP 3 LASTPIN (-6625 3725) SIG_NAME GND\g
J 0
(-6615 3735);
DISPLAY 0.659574 (-6615 3735);
PAINT MONO (-6615 3735);
DISPLAY INVISIBLE (-6615 3735);
FORCEPROP 1 LAST PATH I25
J 0
(-6550 3675);
DISPLAY 0.872340 (-6550 3675);
PAINT AQUA (-6550 3675);
DISPLAY INVISIBLE (-6550 3675);
FORCEPROP 1 LAST HDL_POWER GND
J 1
(-6600 3600);
DISPLAY 0.872340 (-6600 3600);
PAINT GREEN (-6600 3600);
DISPLAY INVISIBLE (-6600 3600);
FORCEPROP 2 LAST CDS_LIB pure_quanta_power
J 0
(-6625 3675);
PAINT MONO (-6625 3675);
DISPLAY INVISIBLE (-6625 3675);
FORCEADD UNIVERSAL_GND..1
(-8650 4750);
FORCEPROP 3 LASTPIN (-8650 4800) SIG_NAME GND\g
J 0
(-8640 4810);
DISPLAY 0.659574 (-8640 4810);
PAINT MONO (-8640 4810);
DISPLAY INVISIBLE (-8640 4810);
FORCEPROP 1 LAST PATH I26
J 0
(-8575 4750);
DISPLAY 0.872340 (-8575 4750);
PAINT AQUA (-8575 4750);
DISPLAY INVISIBLE (-8575 4750);
FORCEPROP 1 LAST HDL_POWER GND
J 1
(-8625 4675);
DISPLAY 0.872340 (-8625 4675);
PAINT GREEN (-8625 4675);
DISPLAY INVISIBLE (-8625 4675);
FORCEPROP 2 LAST CDS_LIB pure_quanta_power
J 0
(-8650 4750);
DISPLAY INVISIBLE (-8650 4750);
FORCEADD OFFPAGE..5
(-8625 5550);
FORCEPROP 2 LAST $XR0 27 
J 0
(-8879 5550);
DISPLAY 0.638298 (-8879 5550);
PAINT MONO (-8879 5550);
FORCEPROP 2 LAST PATH I27
J 0
(-8825 5600);
DISPLAY 0.680851 (-8825 5600);
DISPLAY INVISIBLE (-8825 5600);
FORCEPROP 1 LAST COMMENT_BODY TRUE
J 0
(-8525 5475);
DISPLAY 0.872340 (-8525 5475);
PAINT GREEN (-8525 5475);
DISPLAY INVISIBLE (-8525 5475);
FORCEPROP 1 LAST OFFPAGE TRUE
J 0
(-8300 5425);
DISPLAY 0.872340 (-8300 5425);
PAINT GREEN (-8300 5425);
DISPLAY INVISIBLE (-8300 5425);
FORCEPROP 2 LAST CDS_LIB standard
J 0
(-8625 5550);
DISPLAY INVISIBLE (-8625 5550);
FORCEADD Q_RES..2
(-8650 5200);
FORCEPROP 1 LAST LOCATION PR40
J 0
(-8605 5325);
DISPLAY 0.489362 (-8605 5325);
PAINT SKYBLUE (-8605 5325);
FORCEPROP 0 LAST $SEC 1
J 0
(-8600 5350);
DISPLAY 0.680851 (-8600 5350);
PAINT MONO (-8600 5350);
DISPLAY INVISIBLE (-8600 5350);
FORCEPROP 0 LAST CDS_SEC 1
J 0
(-8600 5350);
DISPLAY 1.021277 (-8600 5350);
DISPLAY INVISIBLE (-8600 5350);
FORCEPROP 1 LASTPIN (-8650 5300) $PN 1
J 0
(-8645 5262);
DISPLAY 0.489362 (-8645 5262);
PAINT MONO (-8645 5262);
FORCEPROP 1 LASTPIN (-8650 5100) $PN 2
J 0
(-8645 5110);
DISPLAY 0.489362 (-8645 5110);
PAINT MONO (-8645 5110);
FORCEPROP 1 LAST WATTAGE 1/16W
J 0
(-8625 5125);
DISPLAY 0.489362 (-8625 5125);
PAINT SKYBLUE (-8625 5125);
FORCEPROP 1 LAST VALUE 0
J 0
(-8620 5225);
DISPLAY 0.489362 (-8620 5225);
PAINT SKYBLUE (-8620 5225);
FORCEPROP 1 LAST PACK_TYPE 0402LF
J 0
(-8625 5025);
DISPLAY 0.489362 (-8625 5025);
PAINT SKYBLUE (-8625 5025);
FORCEPROP 1 LAST MATERIAL CHIP
J 0
(-8625 5075);
DISPLAY 0.489362 (-8625 5075);
PAINT SKYBLUE (-8625 5075);
FORCEPROP 1 LAST TOLERANCE 5%
J 0
(-8620 5175);
DISPLAY 0.489362 (-8620 5175);
PAINT SKYBLUE (-8620 5175);
FORCEPROP 1 LAST PART_NUMBER CS00002JB13
J 0
(-8625 5025);
DISPLAY 0.489362 (-8625 5025);
PAINT SKYBLUE (-8625 5025);
DISPLAY INVISIBLE (-8625 5025);
FORCEPROP 1 LAST PATH I28
J 0
(-8600 5375);
DISPLAY 0.978723 (-8600 5375);
PAINT WHITE (-8600 5375);
DISPLAY INVISIBLE (-8600 5375);
FORCEPROP 2 LAST CDS_LIB pure_quanta
J 0
(-8650 5200);
DISPLAY INVISIBLE (-8650 5200);
FORCEADD OFFPAGE..1
(-8625 5700);
FORCEPROP 2 LAST $XR0 27 
J 0
(-8846 5700);
DISPLAY 0.638298 (-8846 5700);
PAINT MONO (-8846 5700);
FORCEPROP 2 LAST PATH I29
J 0
(-8825 5750);
DISPLAY 0.680851 (-8825 5750);
DISPLAY INVISIBLE (-8825 5750);
FORCEPROP 1 LAST COMMENT_BODY TRUE
J 0
(-8500 5600);
DISPLAY 0.872340 (-8500 5600);
PAINT GREEN (-8500 5600);
DISPLAY INVISIBLE (-8500 5600);
FORCEPROP 1 LAST OFFPAGE TRUE
J 0
(-8300 5575);
DISPLAY 0.872340 (-8300 5575);
PAINT GREEN (-8300 5575);
DISPLAY INVISIBLE (-8300 5575);
FORCEPROP 2 LAST CDS_LIB standard
J 0
(-8625 5700);
DISPLAY INVISIBLE (-8625 5700);
FORCEADD Q_CAP..1
(-8000 1425);
FORCEPROP 1 LAST LOCATION C8066
J 0
(-7950 1525);
DISPLAY 0.489362 (-7950 1525);
PAINT SKYBLUE (-7950 1525);
FORCEPROP 0 LAST $SEC 1
J 0
(-7950 1550);
DISPLAY 0.680851 (-7950 1550);
PAINT MONO (-7950 1550);
DISPLAY INVISIBLE (-7950 1550);
FORCEPROP 0 LAST CDS_SEC 1
J 0
(-7950 1550);
DISPLAY 1.021277 (-7950 1550);
DISPLAY INVISIBLE (-7950 1550);
FORCEPROP 1 LASTPIN (-8000 1525) $PN 1
J 0
(-7990 1505);
DISPLAY 0.489362 (-7990 1505);
PAINT MONO (-7990 1505);
FORCEPROP 1 LASTPIN (-8000 1325) $PN 2
J 0
(-7990 1305);
DISPLAY 0.489362 (-7990 1305);
PAINT MONO (-7990 1305);
FORCEPROP 1 LAST VOLTAGE 50V
J 0
(-7950 1425);
DISPLAY 0.489362 (-7950 1425);
PAINT SKYBLUE (-7950 1425);
FORCEPROP 1 LAST TOLERANCE 5%
J 0
(-7950 1375);
DISPLAY 0.489362 (-7950 1375);
PAINT SKYBLUE (-7950 1375);
FORCEPROP 1 LAST VALUE 1000PF
J 0
(-7950 1475);
DISPLAY 0.489362 (-7950 1475);
PAINT SKYBLUE (-7950 1475);
FORCEPROP 1 LAST PACK_TYPE 0402
J 0
(-7950 1275);
DISPLAY 0.489362 (-7950 1275);
PAINT SKYBLUE (-7950 1275);
FORCEPROP 1 LAST MATERIAL X7R
J 0
(-7950 1325);
DISPLAY 0.489362 (-7950 1325);
PAINT SKYBLUE (-7950 1325);
FORCEPROP 1 LAST PART_NUMBER TMP_QCH21006JB10
J 0
(-7950 1225);
DISPLAY 0.489362 (-7950 1225);
PAINT SKYBLUE (-7950 1225);
DISPLAY INVISIBLE (-7950 1225);
FORCEPROP 1 LAST PATH I3
J 0
(-7950 1575);
DISPLAY 0.978723 (-7950 1575);
PAINT WHITE (-7950 1575);
DISPLAY INVISIBLE (-7950 1575);
FORCEPROP 2 LAST CDS_LIB pure_quanta
J 0
(-8000 1425);
DISPLAY INVISIBLE (-8000 1425);
FORCEADD OFFPAGE..1
(-8625 5850);
FORCEPROP 2 LAST $XR0 27 
J 0
(-8846 5850);
DISPLAY 0.638298 (-8846 5850);
PAINT MONO (-8846 5850);
FORCEPROP 2 LAST PATH I30
J 0
(-8825 5900);
DISPLAY 0.680851 (-8825 5900);
DISPLAY INVISIBLE (-8825 5900);
FORCEPROP 1 LAST COMMENT_BODY TRUE
J 0
(-8500 5750);
DISPLAY 0.872340 (-8500 5750);
PAINT GREEN (-8500 5750);
DISPLAY INVISIBLE (-8500 5750);
FORCEPROP 1 LAST OFFPAGE TRUE
J 0
(-8300 5725);
DISPLAY 0.872340 (-8300 5725);
PAINT GREEN (-8300 5725);
DISPLAY INVISIBLE (-8300 5725);
FORCEPROP 2 LAST CDS_LIB standard
J 0
(-8625 5850);
DISPLAY INVISIBLE (-8625 5850);
FORCEADD OFFPAGE..1
(-8350 4300);
FORCEPROP 2 LAST $XR0 27 
J 0
(-8631 4300);
DISPLAY 0.638298 (-8631 4300);
PAINT MONO (-8631 4300);
FORCEPROP 1 LAST COMMENT_BODY TRUE
J 0
(-8225 4200);
DISPLAY 0.872340 (-8225 4200);
PAINT GREEN (-8225 4200);
DISPLAY INVISIBLE (-8225 4200);
FORCEPROP 1 LAST OFFPAGE TRUE
J 0
(-8025 4175);
DISPLAY 0.872340 (-8025 4175);
PAINT GREEN (-8025 4175);
DISPLAY INVISIBLE (-8025 4175);
FORCEPROP 2 LAST CDS_LIB standard
J 0
(-8350 4300);
DISPLAY INVISIBLE (-8350 4300);
FORCEPROP 2 LAST PATH I31
J 0
(-8625 4350);
DISPLAY 0.680851 (-8625 4350);
DISPLAY INVISIBLE (-8625 4350);
FORCEADD Q_RES..2
(-8425 5200);
FORCEPROP 1 LAST LOCATION R8042
J 0
(-8380 5325);
DISPLAY 0.489362 (-8380 5325);
PAINT SKYBLUE (-8380 5325);
FORCEPROP 0 LAST $SEC 1
J 0
(-8375 5350);
DISPLAY 0.680851 (-8375 5350);
PAINT MONO (-8375 5350);
DISPLAY INVISIBLE (-8375 5350);
FORCEPROP 0 LAST CDS_SEC 1
J 0
(-8375 5350);
DISPLAY 1.021277 (-8375 5350);
DISPLAY INVISIBLE (-8375 5350);
FORCEPROP 1 LASTPIN (-8425 5300) $PN 1
J 0
(-8420 5262);
DISPLAY 0.489362 (-8420 5262);
PAINT MONO (-8420 5262);
FORCEPROP 1 LASTPIN (-8425 5100) $PN 2
J 0
(-8420 5110);
DISPLAY 0.489362 (-8420 5110);
PAINT MONO (-8420 5110);
FORCEPROP 1 LAST MATERIAL EMPTY
J 0
(-8400 5075);
DISPLAY 0.489362 (-8400 5075);
PAINT RED (-8400 5075);
FORCEPROP 1 LAST PACK_TYPE 0402LF
J 0
(-8400 5025);
DISPLAY 0.489362 (-8400 5025);
PAINT SKYBLUE (-8400 5025);
FORCEPROP 1 LAST TOLERANCE 1%
J 0
(-8395 5175);
DISPLAY 0.489362 (-8395 5175);
PAINT SKYBLUE (-8395 5175);
FORCEPROP 1 LAST WATTAGE 1/16W
J 0
(-8400 5125);
DISPLAY 0.489362 (-8400 5125);
PAINT SKYBLUE (-8400 5125);
FORCEPROP 1 LAST VALUE 1K
J 0
(-8395 5225);
DISPLAY 0.489362 (-8395 5225);
PAINT SKYBLUE (-8395 5225);
FORCEPROP 1 LAST PART_NUMBER CS21002FB06
J 0
(-8400 5025);
DISPLAY 0.489362 (-8400 5025);
PAINT SKYBLUE (-8400 5025);
DISPLAY INVISIBLE (-8400 5025);
FORCEPROP 1 LAST PATH I32
J 0
(-8375 5375);
DISPLAY 0.978723 (-8375 5375);
PAINT WHITE (-8375 5375);
DISPLAY INVISIBLE (-8375 5375);
FORCEPROP 2 LAST CDS_LIB pure_quanta
J 0
(-8425 5200);
DISPLAY INVISIBLE (-8425 5200);
FORCEADD Q_CAP..1
(-8250 5200);
FORCEPROP 1 LAST LOCATION C303
J 0
(-8200 5300);
DISPLAY 0.489362 (-8200 5300);
PAINT SKYBLUE (-8200 5300);
FORCEPROP 0 LAST $SEC 1
J 0
(-8200 5325);
DISPLAY 0.680851 (-8200 5325);
PAINT MONO (-8200 5325);
DISPLAY INVISIBLE (-8200 5325);
FORCEPROP 0 LAST CDS_SEC 1
J 0
(-8200 5325);
DISPLAY 1.021277 (-8200 5325);
DISPLAY INVISIBLE (-8200 5325);
FORCEPROP 1 LASTPIN (-8250 5300) $PN 1
J 0
(-8240 5280);
DISPLAY 0.489362 (-8240 5280);
PAINT MONO (-8240 5280);
FORCEPROP 1 LASTPIN (-8250 5100) $PN 2
J 0
(-8240 5080);
DISPLAY 0.489362 (-8240 5080);
PAINT MONO (-8240 5080);
FORCEPROP 1 LAST VOLTAGE 50V
J 0
(-8200 5200);
DISPLAY 0.489362 (-8200 5200);
PAINT SKYBLUE (-8200 5200);
FORCEPROP 1 LAST MATERIAL EMPTY
J 0
(-8200 5100);
DISPLAY 0.489362 (-8200 5100);
PAINT RED (-8200 5100);
FORCEPROP 1 LAST VALUE 10PF
J 0
(-8200 5250);
DISPLAY 0.489362 (-8200 5250);
PAINT SKYBLUE (-8200 5250);
FORCEPROP 1 LAST PACK_TYPE 0402
J 0
(-8200 5000);
DISPLAY 0.489362 (-8200 5000);
PAINT SKYBLUE (-8200 5000);
FORCEPROP 1 LAST TOLERANCE 5%
J 0
(-8200 5150);
DISPLAY 0.489362 (-8200 5150);
PAINT SKYBLUE (-8200 5150);
FORCEPROP 1 LAST PART_NUMBER CH01006JB08
J 0
(-8200 5050);
DISPLAY 0.489362 (-8200 5050);
PAINT SKYBLUE (-8200 5050);
DISPLAY INVISIBLE (-8200 5050);
FORCEPROP 1 LAST PATH I33
J 0
(-8200 5350);
DISPLAY 0.978723 (-8200 5350);
PAINT WHITE (-8200 5350);
DISPLAY INVISIBLE (-8200 5350);
FORCEPROP 2 LAST CDS_LIB pure_quanta
J 0
(-8250 5200);
DISPLAY INVISIBLE (-8250 5200);
FORCEADD Q_CAP..1
(-8075 5200);
FORCEPROP 1 LAST LOCATION C304
J 0
(-8025 5300);
DISPLAY 0.489362 (-8025 5300);
PAINT SKYBLUE (-8025 5300);
FORCEPROP 0 LAST $SEC 1
J 0
(-8025 5325);
DISPLAY 0.680851 (-8025 5325);
PAINT MONO (-8025 5325);
DISPLAY INVISIBLE (-8025 5325);
FORCEPROP 0 LAST CDS_SEC 1
J 0
(-8025 5325);
DISPLAY 1.021277 (-8025 5325);
DISPLAY INVISIBLE (-8025 5325);
FORCEPROP 1 LASTPIN (-8075 5300) $PN 1
J 0
(-8065 5280);
DISPLAY 0.489362 (-8065 5280);
PAINT MONO (-8065 5280);
FORCEPROP 1 LASTPIN (-8075 5100) $PN 2
J 0
(-8065 5080);
DISPLAY 0.489362 (-8065 5080);
PAINT MONO (-8065 5080);
FORCEPROP 1 LAST MATERIAL EMPTY
J 0
(-8025 5100);
DISPLAY 0.489362 (-8025 5100);
PAINT RED (-8025 5100);
FORCEPROP 1 LAST TOLERANCE 5%
J 0
(-8025 5150);
DISPLAY 0.489362 (-8025 5150);
PAINT SKYBLUE (-8025 5150);
FORCEPROP 1 LAST VALUE 10PF
J 0
(-8025 5250);
DISPLAY 0.489362 (-8025 5250);
PAINT SKYBLUE (-8025 5250);
FORCEPROP 1 LAST PACK_TYPE 0402
J 0
(-8025 5000);
DISPLAY 0.489362 (-8025 5000);
PAINT SKYBLUE (-8025 5000);
FORCEPROP 1 LAST VOLTAGE 50V
J 0
(-8025 5200);
DISPLAY 0.489362 (-8025 5200);
PAINT SKYBLUE (-8025 5200);
FORCEPROP 1 LAST PART_NUMBER CH01006JB08
J 0
(-8025 5050);
DISPLAY 0.489362 (-8025 5050);
PAINT SKYBLUE (-8025 5050);
DISPLAY INVISIBLE (-8025 5050);
FORCEPROP 1 LAST PATH I34
J 0
(-8025 5350);
DISPLAY 0.978723 (-8025 5350);
PAINT WHITE (-8025 5350);
DISPLAY INVISIBLE (-8025 5350);
FORCEPROP 2 LAST CDS_LIB pure_quanta
J 0
(-8075 5200);
DISPLAY INVISIBLE (-8075 5200);
FORCEADD Q_CAP..1
(-7825 5200);
FORCEPROP 1 LAST LOCATION C305
J 0
(-7725 5300);
DISPLAY 0.489362 (-7725 5300);
PAINT SKYBLUE (-7725 5300);
FORCEPROP 0 LAST $SEC 1
J 0
(-7775 5325);
DISPLAY 0.680851 (-7775 5325);
PAINT MONO (-7775 5325);
DISPLAY INVISIBLE (-7775 5325);
FORCEPROP 0 LAST CDS_SEC 1
J 0
(-7775 5325);
DISPLAY 1.021277 (-7775 5325);
DISPLAY INVISIBLE (-7775 5325);
FORCEPROP 1 LASTPIN (-7825 5300) $PN 1
J 0
(-7815 5280);
DISPLAY 0.489362 (-7815 5280);
PAINT MONO (-7815 5280);
FORCEPROP 1 LASTPIN (-7825 5100) $PN 2
J 0
(-7815 5080);
DISPLAY 0.489362 (-7815 5080);
PAINT MONO (-7815 5080);
FORCEPROP 1 LAST TOLERANCE 5%
J 0
(-7725 5150);
DISPLAY 0.489362 (-7725 5150);
PAINT SKYBLUE (-7725 5150);
FORCEPROP 1 LAST MATERIAL EMPTY
J 0
(-7725 5100);
DISPLAY 0.489362 (-7725 5100);
PAINT RED (-7725 5100);
FORCEPROP 1 LAST VOLTAGE 50V
J 0
(-7725 5200);
DISPLAY 0.489362 (-7725 5200);
PAINT SKYBLUE (-7725 5200);
FORCEPROP 1 LAST PACK_TYPE 0402
J 0
(-7725 5000);
DISPLAY 0.489362 (-7725 5000);
PAINT SKYBLUE (-7725 5000);
FORCEPROP 1 LAST VALUE 10PF
J 0
(-7725 5250);
DISPLAY 0.489362 (-7725 5250);
PAINT SKYBLUE (-7725 5250);
FORCEPROP 1 LAST PART_NUMBER CH01006JB08
J 0
(-7725 5050);
DISPLAY 0.489362 (-7725 5050);
PAINT SKYBLUE (-7725 5050);
DISPLAY INVISIBLE (-7725 5050);
FORCEPROP 1 LAST PATH I35
J 0
(-7775 5350);
DISPLAY 0.978723 (-7775 5350);
PAINT WHITE (-7775 5350);
DISPLAY INVISIBLE (-7775 5350);
FORCEPROP 2 LAST CDS_LIB pure_quanta
J 0
(-7825 5200);
DISPLAY INVISIBLE (-7825 5200);
FORCEADD Q_RES..1
(-7100 4450);
FORCEPROP 1 LAST LOCATION PR51
J 0
(-7300 4450);
DISPLAY 0.489362 (-7300 4450);
PAINT SKYBLUE (-7300 4450);
FORCEPROP 2 LAST $SEC 1
J 0
(-7150 4650);
DISPLAY 0.680851 (-7150 4650);
PAINT MONO (-7150 4650);
DISPLAY INVISIBLE (-7150 4650);
FORCEPROP 2 LAST CDS_SEC 1
J 0
(-7150 4650);
DISPLAY 1.021277 (-7150 4650);
DISPLAY INVISIBLE (-7150 4650);
FORCEPROP 1 LASTPIN (-7200 4450) $PN 1
J 0
(-7188 4462);
DISPLAY 0.489362 (-7188 4462);
FORCEPROP 1 LASTPIN (-7000 4450) $PN 2
J 0
(-7038 4462);
DISPLAY 0.489362 (-7038 4462);
FORCEPROP 1 LAST PACK_TYPE 0402LF
J 0
(-6800 4450);
DISPLAY 0.489362 (-6800 4450);
PAINT SKYBLUE (-6800 4450);
FORCEPROP 1 LAST TOLERANCE 1%
J 0
(-6875 4450);
DISPLAY 0.489362 (-6875 4450);
PAINT SKYBLUE (-6875 4450);
FORCEPROP 1 LAST VALUE 49.9
J 2
(-6925 4500);
DISPLAY 0.489362 (-6925 4500);
PAINT SKYBLUE (-6925 4500);
FORCEPROP 1 LAST MATERIAL CHIP
J 0
(-6975 4550);
DISPLAY 0.489362 (-6975 4550);
PAINT SKYBLUE (-6975 4550);
FORCEPROP 1 LAST WATTAGE 1/16W
J 2
(-6725 4550);
DISPLAY 0.489362 (-6725 4550);
PAINT SKYBLUE (-6725 4550);
FORCEPROP 1 LAST PART_NUMBER CS04992FB07
J 0
(-6900 4500);
DISPLAY 0.489362 (-6900 4500);
PAINT SKYBLUE (-6900 4500);
DISPLAY INVISIBLE (-6900 4500);
FORCEPROP 1 LAST PATH I36
J 0
(-7150 4600);
DISPLAY 0.978723 (-7150 4600);
PAINT WHITE (-7150 4600);
DISPLAY INVISIBLE (-7150 4600);
FORCEPROP 2 LAST CDS_LIB pure_quanta
J 0
(-7100 4450);
PAINT MONO (-7100 4450);
DISPLAY INVISIBLE (-7100 4450);
FORCEADD OFFPAGE..6
(-6800 5000);
FORCEPROP 2 LAST $XR0 151 
J 0
(-7110 5000);
DISPLAY 0.638298 (-7110 5000);
PAINT MONO (-7110 5000);
FORCEPROP 2 LAST PATH I37
J 0
(-7075 5050);
DISPLAY 0.680851 (-7075 5050);
DISPLAY INVISIBLE (-7075 5050);
FORCEPROP 1 LAST COMMENT_BODY TRUE
J 0
(-6700 4925);
DISPLAY 0.872340 (-6700 4925);
PAINT GREEN (-6700 4925);
DISPLAY INVISIBLE (-6700 4925);
FORCEPROP 1 LAST OFFPAGE TRUE
J 0
(-6475 4875);
DISPLAY 0.872340 (-6475 4875);
PAINT GREEN (-6475 4875);
DISPLAY INVISIBLE (-6475 4875);
FORCEPROP 2 LAST CDS_LIB standard
J 0
(-6800 5000);
DISPLAY INVISIBLE (-6800 5000);
FORCEADD OFFPAGE..5
(-6800 4850);
FORCEPROP 2 LAST $XR0 83 
J 0
(-7054 4850);
DISPLAY 0.638298 (-7054 4850);
PAINT MONO (-7054 4850);
FORCEPROP 2 LAST $XR1 82 
J 0
(-7144 4850);
DISPLAY 0.638298 (-7144 4850);
PAINT MONO (-7144 4850);
FORCEPROP 2 LAST PATH I38
J 0
(-7050 4900);
DISPLAY 0.680851 (-7050 4900);
DISPLAY INVISIBLE (-7050 4900);
FORCEPROP 1 LAST COMMENT_BODY TRUE
J 0
(-6700 4775);
DISPLAY 0.872340 (-6700 4775);
PAINT GREEN (-6700 4775);
DISPLAY INVISIBLE (-6700 4775);
FORCEPROP 1 LAST OFFPAGE TRUE
J 0
(-6475 4725);
DISPLAY 0.872340 (-6475 4725);
PAINT GREEN (-6475 4725);
DISPLAY INVISIBLE (-6475 4725);
FORCEPROP 2 LAST CDS_LIB standard
J 0
(-6800 4850);
DISPLAY INVISIBLE (-6800 4850);
FORCEADD OFFPAGE..1
(-6800 5150);
FORCEPROP 2 LAST $XR0 151 
J 0
(-7082 5150);
DISPLAY 0.638298 (-7082 5150);
PAINT MONO (-7082 5150);
FORCEPROP 2 LAST PATH I39
J 0
(-7050 5200);
DISPLAY 0.680851 (-7050 5200);
DISPLAY INVISIBLE (-7050 5200);
FORCEPROP 1 LAST COMMENT_BODY TRUE
J 0
(-6675 5050);
DISPLAY 0.872340 (-6675 5050);
PAINT GREEN (-6675 5050);
DISPLAY INVISIBLE (-6675 5050);
FORCEPROP 1 LAST OFFPAGE TRUE
J 0
(-6475 5025);
DISPLAY 0.872340 (-6475 5025);
PAINT GREEN (-6475 5025);
DISPLAY INVISIBLE (-6475 5025);
FORCEPROP 2 LAST CDS_LIB standard
J 0
(-6800 5150);
DISPLAY INVISIBLE (-6800 5150);
FORCEADD UNIVERSAL_GND..1
(-8000 1175);
FORCEPROP 3 LASTPIN (-8000 1225) SIG_NAME GND\g
J 0
(-7990 1235);
DISPLAY 0.659574 (-7990 1235);
PAINT MONO (-7990 1235);
DISPLAY INVISIBLE (-7990 1235);
FORCEPROP 1 LAST PATH I4
J 0
(-7925 1175);
DISPLAY 0.872340 (-7925 1175);
PAINT AQUA (-7925 1175);
DISPLAY INVISIBLE (-7925 1175);
FORCEPROP 1 LAST HDL_POWER GND
J 1
(-7975 1100);
DISPLAY 0.872340 (-7975 1100);
PAINT GREEN (-7975 1100);
DISPLAY INVISIBLE (-7975 1100);
FORCEPROP 2 LAST CDS_LIB pure_quanta_power
J 0
(-8000 1175);
DISPLAY INVISIBLE (-8000 1175);
FORCEADD Q_RES..2
(-8550 6175);
FORCEPROP 1 LAST LOCATION PR41
J 0
(-8505 6300);
DISPLAY 0.489362 (-8505 6300);
PAINT SKYBLUE (-8505 6300);
FORCEPROP 0 LAST $SEC 1
J 0
(-8500 6325);
DISPLAY 0.680851 (-8500 6325);
PAINT MONO (-8500 6325);
DISPLAY INVISIBLE (-8500 6325);
FORCEPROP 0 LAST CDS_SEC 1
J 0
(-8500 6325);
DISPLAY 1.021277 (-8500 6325);
DISPLAY INVISIBLE (-8500 6325);
FORCEPROP 1 LASTPIN (-8550 6275) $PN 1
J 0
(-8545 6237);
DISPLAY 0.489362 (-8545 6237);
PAINT MONO (-8545 6237);
FORCEPROP 1 LASTPIN (-8550 6075) $PN 2
J 0
(-8545 6085);
DISPLAY 0.489362 (-8545 6085);
PAINT MONO (-8545 6085);
FORCEPROP 1 LAST MATERIAL EMPTY
J 0
(-8525 6050);
DISPLAY 0.489362 (-8525 6050);
PAINT RED (-8525 6050);
FORCEPROP 1 LAST WATTAGE 1/16W
J 0
(-8525 6100);
DISPLAY 0.489362 (-8525 6100);
PAINT SKYBLUE (-8525 6100);
FORCEPROP 1 LAST TOLERANCE 1%
J 0
(-8520 6150);
DISPLAY 0.489362 (-8520 6150);
PAINT SKYBLUE (-8520 6150);
FORCEPROP 1 LAST VALUE 1K
J 0
(-8520 6200);
DISPLAY 0.489362 (-8520 6200);
PAINT SKYBLUE (-8520 6200);
FORCEPROP 1 LAST PACK_TYPE 0402LF
J 0
(-8525 6000);
DISPLAY 0.489362 (-8525 6000);
PAINT SKYBLUE (-8525 6000);
FORCEPROP 1 LAST PART_NUMBER CS21002FB06
J 0
(-8525 6000);
DISPLAY 0.489362 (-8525 6000);
PAINT SKYBLUE (-8525 6000);
DISPLAY INVISIBLE (-8525 6000);
FORCEPROP 1 LAST PATH I40
J 0
(-8500 6350);
DISPLAY 0.978723 (-8500 6350);
PAINT WHITE (-8500 6350);
DISPLAY INVISIBLE (-8500 6350);
FORCEPROP 2 LAST CDS_LIB pure_quanta
J 0
(-8550 6175);
DISPLAY INVISIBLE (-8550 6175);
FORCEADD VCC_CORE..1
(-8550 6525);
FORCEPROP 3 LASTPIN (-8550 6475) SIG_NAME PVDD18_S5_P0\g
J 0
(-8540 6485);
DISPLAY 0.659574 (-8540 6485);
PAINT MONO (-8540 6485);
DISPLAY INVISIBLE (-8540 6485);
FORCEPROP 1 LAST HDL_POWER PVDD18_S5_P0
J 1
(-8550 6575);
DISPLAY 0.489362 (-8550 6575);
PAINT GREEN (-8550 6575);
FORCEPROP 2 LAST CDS_LIB pure_quanta_power
J 0
(-8550 6525);
DISPLAY INVISIBLE (-8550 6525);
FORCEPROP 1 LAST PATH I41
J 0
(-8500 6550);
DISPLAY 0.872340 (-8500 6550);
PAINT AQUA (-8500 6550);
DISPLAY INVISIBLE (-8500 6550);
FORCEADD Q_RES..2
(-8200 6175);
FORCEPROP 1 LAST LOCATION R8043
J 0
(-8150 6300);
DISPLAY 0.489362 (-8150 6300);
PAINT SKYBLUE (-8150 6300);
FORCEPROP 0 LAST $SEC 1
J 0
(-8150 6325);
DISPLAY 0.680851 (-8150 6325);
PAINT MONO (-8150 6325);
DISPLAY INVISIBLE (-8150 6325);
FORCEPROP 0 LAST CDS_SEC 1
J 0
(-8150 6325);
DISPLAY 1.021277 (-8150 6325);
DISPLAY INVISIBLE (-8150 6325);
FORCEPROP 1 LASTPIN (-8200 6275) $PN 1
J 0
(-8195 6237);
DISPLAY 0.489362 (-8195 6237);
PAINT MONO (-8195 6237);
FORCEPROP 1 LASTPIN (-8200 6075) $PN 2
J 0
(-8195 6085);
DISPLAY 0.489362 (-8195 6085);
PAINT MONO (-8195 6085);
FORCEPROP 1 LAST TOLERANCE 1%
J 0
(-8170 6150);
DISPLAY 0.489362 (-8170 6150);
PAINT SKYBLUE (-8170 6150);
FORCEPROP 1 LAST WATTAGE 1/16W
J 0
(-8175 6100);
DISPLAY 0.489362 (-8175 6100);
PAINT SKYBLUE (-8175 6100);
FORCEPROP 1 LAST PACK_TYPE 0402LF
J 0
(-8175 6000);
DISPLAY 0.489362 (-8175 6000);
PAINT SKYBLUE (-8175 6000);
FORCEPROP 1 LAST MATERIAL EMPTY
J 0
(-8175 6050);
DISPLAY 0.489362 (-8175 6050);
PAINT RED (-8175 6050);
FORCEPROP 1 LAST VALUE 1K
J 0
(-8170 6200);
DISPLAY 0.489362 (-8170 6200);
PAINT SKYBLUE (-8170 6200);
FORCEPROP 1 LAST PART_NUMBER CS21002FB06
J 0
(-8175 6000);
DISPLAY 0.489362 (-8175 6000);
PAINT SKYBLUE (-8175 6000);
DISPLAY INVISIBLE (-8175 6000);
FORCEPROP 1 LAST PATH I42
J 0
(-8150 6350);
DISPLAY 0.978723 (-8150 6350);
PAINT WHITE (-8150 6350);
DISPLAY INVISIBLE (-8150 6350);
FORCEPROP 2 LAST CDS_LIB pure_quanta
J 0
(-8200 6175);
DISPLAY INVISIBLE (-8200 6175);
FORCEADD Q_RES..2
(-8000 6175);
FORCEPROP 1 LAST LOCATION R8045
J 0
(-7955 6300);
DISPLAY 0.489362 (-7955 6300);
PAINT SKYBLUE (-7955 6300);
FORCEPROP 0 LAST $SEC 1
J 0
(-7950 6325);
DISPLAY 0.680851 (-7950 6325);
PAINT MONO (-7950 6325);
DISPLAY INVISIBLE (-7950 6325);
FORCEPROP 0 LAST CDS_SEC 1
J 0
(-7950 6325);
DISPLAY 1.021277 (-7950 6325);
DISPLAY INVISIBLE (-7950 6325);
FORCEPROP 1 LASTPIN (-8000 6275) $PN 1
J 0
(-7995 6237);
DISPLAY 0.489362 (-7995 6237);
PAINT MONO (-7995 6237);
FORCEPROP 1 LASTPIN (-8000 6075) $PN 2
J 0
(-7995 6085);
DISPLAY 0.489362 (-7995 6085);
PAINT MONO (-7995 6085);
FORCEPROP 1 LAST TOLERANCE 1%
J 0
(-7970 6150);
DISPLAY 0.489362 (-7970 6150);
PAINT SKYBLUE (-7970 6150);
FORCEPROP 1 LAST WATTAGE 1/16W
J 0
(-7975 6100);
DISPLAY 0.489362 (-7975 6100);
PAINT SKYBLUE (-7975 6100);
FORCEPROP 1 LAST MATERIAL EMPTY
J 0
(-7975 6050);
DISPLAY 0.489362 (-7975 6050);
PAINT RED (-7975 6050);
FORCEPROP 1 LAST VALUE 1K
J 0
(-7970 6200);
DISPLAY 0.489362 (-7970 6200);
PAINT SKYBLUE (-7970 6200);
FORCEPROP 1 LAST PACK_TYPE 0402LF
J 0
(-7975 6000);
DISPLAY 0.489362 (-7975 6000);
PAINT SKYBLUE (-7975 6000);
FORCEPROP 1 LAST PART_NUMBER CS21002FB06
J 0
(-7975 6000);
DISPLAY 0.489362 (-7975 6000);
PAINT SKYBLUE (-7975 6000);
DISPLAY INVISIBLE (-7975 6000);
FORCEPROP 1 LAST PATH I43
J 0
(-7950 6350);
DISPLAY 0.978723 (-7950 6350);
PAINT WHITE (-7950 6350);
DISPLAY INVISIBLE (-7950 6350);
FORCEPROP 2 LAST CDS_LIB pure_quanta
J 0
(-8000 6175);
DISPLAY INVISIBLE (-8000 6175);
FORCEADD Q_RES..2
(-7750 6175);
FORCEPROP 1 LAST LOCATION R8048
J 0
(-7705 6300);
DISPLAY 0.489362 (-7705 6300);
PAINT SKYBLUE (-7705 6300);
FORCEPROP 0 LAST $SEC 1
J 0
(-7700 6325);
DISPLAY 0.680851 (-7700 6325);
PAINT MONO (-7700 6325);
DISPLAY INVISIBLE (-7700 6325);
FORCEPROP 0 LAST CDS_SEC 1
J 0
(-7700 6325);
DISPLAY 1.021277 (-7700 6325);
DISPLAY INVISIBLE (-7700 6325);
FORCEPROP 1 LASTPIN (-7750 6275) $PN 1
J 0
(-7745 6237);
DISPLAY 0.489362 (-7745 6237);
PAINT MONO (-7745 6237);
FORCEPROP 1 LASTPIN (-7750 6075) $PN 2
J 0
(-7745 6085);
DISPLAY 0.489362 (-7745 6085);
PAINT MONO (-7745 6085);
FORCEPROP 1 LAST MATERIAL EMPTY
J 0
(-7725 6050);
DISPLAY 0.489362 (-7725 6050);
PAINT RED (-7725 6050);
FORCEPROP 1 LAST PACK_TYPE 0402LF
J 0
(-7725 5950);
DISPLAY 0.489362 (-7725 5950);
PAINT SKYBLUE (-7725 5950);
FORCEPROP 1 LAST TOLERANCE 1%
J 0
(-7720 6150);
DISPLAY 0.489362 (-7720 6150);
PAINT SKYBLUE (-7720 6150);
FORCEPROP 1 LAST VALUE 1K
J 0
(-7720 6200);
DISPLAY 0.489362 (-7720 6200);
PAINT SKYBLUE (-7720 6200);
FORCEPROP 1 LAST WATTAGE 1/16W
J 0
(-7725 6100);
DISPLAY 0.489362 (-7725 6100);
PAINT SKYBLUE (-7725 6100);
FORCEPROP 1 LAST PART_NUMBER CS21002FB06
J 0
(-7725 6000);
DISPLAY 0.489362 (-7725 6000);
PAINT SKYBLUE (-7725 6000);
DISPLAY INVISIBLE (-7725 6000);
FORCEPROP 1 LAST PATH I44
J 0
(-7700 6350);
DISPLAY 0.978723 (-7700 6350);
PAINT WHITE (-7700 6350);
DISPLAY INVISIBLE (-7700 6350);
FORCEPROP 2 LAST CDS_LIB pure_quanta
J 0
(-7750 6175);
DISPLAY INVISIBLE (-7750 6175);
FORCEADD OFFPAGE..5
(-7275 6300);
FORCEPROP 2 LAST $XR0 82 
J 0
(-7529 6300);
DISPLAY 0.638298 (-7529 6300);
PAINT MONO (-7529 6300);
FORCEPROP 2 LAST PATH I45
J 0
(-7475 6350);
DISPLAY 0.680851 (-7475 6350);
DISPLAY INVISIBLE (-7475 6350);
FORCEPROP 1 LAST COMMENT_BODY TRUE
J 0
(-7175 6225);
DISPLAY 0.872340 (-7175 6225);
PAINT GREEN (-7175 6225);
DISPLAY INVISIBLE (-7175 6225);
FORCEPROP 1 LAST OFFPAGE TRUE
J 0
(-6950 6175);
DISPLAY 0.872340 (-6950 6175);
PAINT GREEN (-6950 6175);
DISPLAY INVISIBLE (-6950 6175);
FORCEPROP 2 LAST CDS_LIB standard
J 0
(-7275 6300);
DISPLAY INVISIBLE (-7275 6300);
FORCEADD OFFPAGE..1
(-7275 6150);
FORCEPROP 2 LAST $XR0 82 
J 0
(-7496 6150);
DISPLAY 0.638298 (-7496 6150);
PAINT MONO (-7496 6150);
FORCEPROP 2 LAST PATH I46
J 0
(-7475 6200);
DISPLAY 0.680851 (-7475 6200);
DISPLAY INVISIBLE (-7475 6200);
FORCEPROP 1 LAST COMMENT_BODY TRUE
J 0
(-7150 6050);
DISPLAY 0.872340 (-7150 6050);
PAINT GREEN (-7150 6050);
DISPLAY INVISIBLE (-7150 6050);
FORCEPROP 1 LAST OFFPAGE TRUE
J 0
(-6950 6025);
DISPLAY 0.872340 (-6950 6025);
PAINT GREEN (-6950 6025);
DISPLAY INVISIBLE (-6950 6025);
FORCEPROP 2 LAST CDS_LIB standard
J 0
(-7275 6150);
DISPLAY INVISIBLE (-7275 6150);
FORCEADD VCC_CORE..1
(-6900 6550);
FORCEPROP 3 LASTPIN (-6900 6500) SIG_NAME P3V3_AUX\g
J 0
(-6890 6510);
DISPLAY 0.659574 (-6890 6510);
PAINT MONO (-6890 6510);
DISPLAY INVISIBLE (-6890 6510);
FORCEPROP 1 LAST HDL_POWER P3V3_AUX
J 1
(-6900 6600);
DISPLAY 0.489362 (-6900 6600);
PAINT GREEN (-6900 6600);
FORCEPROP 1 LAST PATH I47
J 0
(-6850 6575);
DISPLAY 0.872340 (-6850 6575);
PAINT AQUA (-6850 6575);
DISPLAY INVISIBLE (-6850 6575);
FORCEPROP 2 LAST CDS_LIB pure_quanta_power
J 0
(-6900 6550);
DISPLAY INVISIBLE (-6900 6550);
FORCEADD OFFPAGE..5
(-6450 2300);
FORCEPROP 2 LAST $XR0 82 
J 0
(-6674 2300);
DISPLAY 0.638298 (-6674 2300);
PAINT MONO (-6674 2300);
FORCEPROP 2 LAST PATH I48
J 0
(-6700 2350);
DISPLAY 0.680851 (-6700 2350);
DISPLAY INVISIBLE (-6700 2350);
FORCEPROP 1 LAST COMMENT_BODY TRUE
J 0
(-6350 2225);
DISPLAY 0.872340 (-6350 2225);
PAINT GREEN (-6350 2225);
DISPLAY INVISIBLE (-6350 2225);
FORCEPROP 1 LAST OFFPAGE TRUE
J 0
(-6125 2175);
DISPLAY 0.872340 (-6125 2175);
PAINT GREEN (-6125 2175);
DISPLAY INVISIBLE (-6125 2175);
FORCEPROP 2 LAST CDS_LIB standard
J 0
(-6450 2300);
DISPLAY INVISIBLE (-6450 2300);
FORCEADD UNIVERSAL_GND..1
(-6200 475);
FORCEPROP 3 LASTPIN (-6200 525) SIG_NAME GND\g
J 0
(-6190 535);
DISPLAY 0.659574 (-6190 535);
PAINT MONO (-6190 535);
DISPLAY INVISIBLE (-6190 535);
FORCEPROP 1 LAST PATH I49
J 0
(-6125 475);
DISPLAY 0.872340 (-6125 475);
PAINT AQUA (-6125 475);
DISPLAY INVISIBLE (-6125 475);
FORCEPROP 1 LAST HDL_POWER GND
J 1
(-6175 400);
DISPLAY 0.872340 (-6175 400);
PAINT GREEN (-6175 400);
DISPLAY INVISIBLE (-6175 400);
FORCEPROP 2 LAST CDS_LIB pure_quanta_power
J 0
(-6200 475);
PAINT MONO (-6200 475);
DISPLAY INVISIBLE (-6200 475);
FORCEADD OFFPAGE..5
(-7525 1100);
FORCEPROP 2 LAST $XR0 81 
J 0
(-7749 1100);
DISPLAY 0.638298 (-7749 1100);
PAINT MONO (-7749 1100);
FORCEPROP 2 LAST PATH I5
J 0
(-7725 1150);
DISPLAY 0.680851 (-7725 1150);
DISPLAY INVISIBLE (-7725 1150);
FORCEPROP 1 LAST COMMENT_BODY TRUE
J 0
(-7425 1025);
DISPLAY 0.872340 (-7425 1025);
PAINT GREEN (-7425 1025);
DISPLAY INVISIBLE (-7425 1025);
FORCEPROP 1 LAST OFFPAGE TRUE
J 0
(-7200 975);
DISPLAY 0.872340 (-7200 975);
PAINT GREEN (-7200 975);
DISPLAY INVISIBLE (-7200 975);
FORCEPROP 2 LAST CDS_LIB standard
J 0
(-7525 1100);
DISPLAY INVISIBLE (-7525 1100);
FORCEADD Q_CAP..1
(-6200 800);
FORCEPROP 1 LAST LOCATION PC67
J 0
(-6150 925);
DISPLAY 0.489362 (-6150 925);
PAINT SKYBLUE (-6150 925);
FORCEPROP 0 LAST $SEC 1
J 0
(-6150 975);
DISPLAY 0.680851 (-6150 975);
PAINT MONO (-6150 975);
DISPLAY INVISIBLE (-6150 975);
FORCEPROP 0 LAST CDS_SEC 1
J 0
(-6150 975);
DISPLAY 1.021277 (-6150 975);
DISPLAY INVISIBLE (-6150 975);
FORCEPROP 1 LASTPIN (-6200 900) $PN 1
J 0
(-6190 880);
DISPLAY 0.489362 (-6190 880);
PAINT MONO (-6190 880);
FORCEPROP 1 LASTPIN (-6200 700) $PN 2
J 0
(-6190 680);
DISPLAY 0.489362 (-6190 680);
PAINT MONO (-6190 680);
FORCEPROP 1 LAST VALUE 0.1UF
J 0
(-6150 875);
DISPLAY 0.489362 (-6150 875);
PAINT SKYBLUE (-6150 875);
FORCEPROP 1 LAST VOLTAGE 25V
J 0
(-6150 825);
DISPLAY 0.489362 (-6150 825);
PAINT SKYBLUE (-6150 825);
FORCEPROP 1 LAST PACK_TYPE 0402
J 0
(-6150 675);
DISPLAY 0.489362 (-6150 675);
PAINT SKYBLUE (-6150 675);
FORCEPROP 1 LAST MATERIAL X7R
J 0
(-6150 725);
DISPLAY 0.489362 (-6150 725);
PAINT SKYBLUE (-6150 725);
FORCEPROP 1 LAST TOLERANCE 10%
J 0
(-6150 775);
DISPLAY 0.489362 (-6150 775);
PAINT SKYBLUE (-6150 775);
FORCEPROP 1 LAST PART_NUMBER CH4104K1B00
J 0
(-6150 625);
DISPLAY 0.489362 (-6150 625);
PAINT SKYBLUE (-6150 625);
DISPLAY INVISIBLE (-6150 625);
FORCEPROP 1 LAST PATH I50
J 0
(-6150 950);
DISPLAY 0.978723 (-6150 950);
PAINT WHITE (-6150 950);
DISPLAY INVISIBLE (-6150 950);
FORCEPROP 2 LAST CDS_LIB pure_quanta
J 0
(-6200 800);
DISPLAY INVISIBLE (-6200 800);
FORCEADD Q_RES..1
(-5750 775);
FORCEPROP 1 LAST LOCATION PR74
J 0
(-5775 825);
DISPLAY 0.489362 (-5775 825);
PAINT SKYBLUE (-5775 825);
FORCEPROP 0 LAST $SEC 1
J 0
(-5800 875);
DISPLAY 0.680851 (-5800 875);
PAINT MONO (-5800 875);
DISPLAY INVISIBLE (-5800 875);
FORCEPROP 0 LAST CDS_SEC 1
J 0
(-5800 875);
DISPLAY 1.021277 (-5800 875);
DISPLAY INVISIBLE (-5800 875);
FORCEPROP 1 LASTPIN (-5850 775) $PN 1
J 0
(-5838 787);
DISPLAY 0.489362 (-5838 787);
PAINT MONO (-5838 787);
FORCEPROP 1 LASTPIN (-5650 775) $PN 2
J 0
(-5688 787);
DISPLAY 0.489362 (-5688 787);
PAINT MONO (-5688 787);
FORCEPROP 1 LAST PACK_TYPE 0402LF
J 0
(-5650 825);
DISPLAY 0.489362 (-5650 825);
PAINT SKYBLUE (-5650 825);
FORCEPROP 1 LAST VALUE 0
J 2
(-5875 800);
DISPLAY 0.489362 (-5875 800);
PAINT SKYBLUE (-5875 800);
FORCEPROP 1 LAST TOLERANCE 5%
J 0
(-5625 800);
DISPLAY 0.489362 (-5625 800);
PAINT SKYBLUE (-5625 800);
FORCEPROP 1 LAST MATERIAL CHIP
J 0
(-5650 725);
DISPLAY 0.489362 (-5650 725);
PAINT SKYBLUE (-5650 725);
FORCEPROP 1 LAST WATTAGE 1/16W
J 2
(-5550 700);
DISPLAY 0.489362 (-5550 700);
PAINT SKYBLUE (-5550 700);
FORCEPROP 1 LAST PART_NUMBER CS00002JB13
J 0
(-6025 725);
DISPLAY 0.489362 (-6025 725);
PAINT SKYBLUE (-6025 725);
DISPLAY INVISIBLE (-6025 725);
FORCEPROP 2 LAST CDS_LIB pure_quanta
J 0
(-5750 775);
DISPLAY INVISIBLE (-5750 775);
FORCEPROP 1 LAST PATH I51
J 0
(-5800 925);
DISPLAY 0.978723 (-5800 925);
PAINT WHITE (-5800 925);
DISPLAY INVISIBLE (-5800 925);
FORCEADD VCC_CORE..1
(-5925 850);
FORCEPROP 3 LASTPIN (-5925 800) SIG_NAME P12V_AUX\g
J 0
(-5915 810);
DISPLAY 0.659574 (-5915 810);
PAINT MONO (-5915 810);
DISPLAY INVISIBLE (-5915 810);
FORCEPROP 1 LAST HDL_POWER P12V_AUX
J 1
(-5925 900);
DISPLAY 0.489362 (-5925 900);
PAINT GREEN (-5925 900);
FORCEPROP 1 LAST PATH I52
J 0
(-5875 875);
DISPLAY 0.872340 (-5875 875);
PAINT AQUA (-5875 875);
DISPLAY INVISIBLE (-5875 875);
FORCEPROP 2 LAST CDS_LIB pure_quanta_power
J 0
(-5925 850);
DISPLAY INVISIBLE (-5925 850);
FORCEADD Q_RES..1
(-6375 1050);
FORCEPROP 1 LAST LOCATION R8066
J 0
(-6600 1050);
DISPLAY 0.489362 (-6600 1050);
PAINT SKYBLUE (-6600 1050);
FORCEPROP 0 LAST $SEC 1
J 0
(-6425 1150);
DISPLAY 0.680851 (-6425 1150);
PAINT MONO (-6425 1150);
DISPLAY INVISIBLE (-6425 1150);
FORCEPROP 0 LAST CDS_SEC 1
J 0
(-6425 1150);
DISPLAY 1.021277 (-6425 1150);
DISPLAY INVISIBLE (-6425 1150);
FORCEPROP 1 LASTPIN (-6475 1050) $PN 1
J 0
(-6463 1062);
DISPLAY 0.489362 (-6463 1062);
PAINT MONO (-6463 1062);
FORCEPROP 1 LASTPIN (-6275 1050) $PN 2
J 0
(-6313 1062);
DISPLAY 0.489362 (-6313 1062);
PAINT MONO (-6313 1062);
FORCEPROP 1 LAST WATTAGE 1/16W
J 2
(-6000 1150);
DISPLAY 0.489362 (-6000 1150);
PAINT SKYBLUE (-6000 1150);
FORCEPROP 1 LAST PACK_TYPE 0402LF
J 0
(-6125 1050);
DISPLAY 0.489362 (-6125 1050);
PAINT SKYBLUE (-6125 1050);
FORCEPROP 1 LAST TOLERANCE 5%
J 0
(-6200 1050);
DISPLAY 0.489362 (-6200 1050);
PAINT SKYBLUE (-6200 1050);
FORCEPROP 1 LAST MATERIAL CHIP
J 0
(-6250 1150);
DISPLAY 0.489362 (-6250 1150);
PAINT SKYBLUE (-6250 1150);
FORCEPROP 1 LAST VALUE 33
J 2
(-6225 1050);
DISPLAY 0.489362 (-6225 1050);
PAINT SKYBLUE (-6225 1050);
FORCEPROP 1 LAST PART_NUMBER CS03302JB10
J 0
(-6250 1100);
DISPLAY 0.489362 (-6250 1100);
PAINT SKYBLUE (-6250 1100);
DISPLAY INVISIBLE (-6250 1100);
FORCEPROP 1 LAST PATH I53
J 0
(-6425 1200);
DISPLAY 0.978723 (-6425 1200);
PAINT WHITE (-6425 1200);
DISPLAY INVISIBLE (-6425 1200);
FORCEPROP 2 LAST CDS_LIB pure_quanta
J 0
(-6375 1050);
DISPLAY INVISIBLE (-6375 1050);
FORCEADD Q_RES..1
(-6375 1200);
FORCEPROP 1 LAST LOCATION R8065
J 0
(-6600 1200);
DISPLAY 0.489362 (-6600 1200);
PAINT SKYBLUE (-6600 1200);
FORCEPROP 0 LAST $SEC 1
J 0
(-6425 1300);
DISPLAY 0.680851 (-6425 1300);
PAINT MONO (-6425 1300);
DISPLAY INVISIBLE (-6425 1300);
FORCEPROP 0 LAST CDS_SEC 1
J 0
(-6425 1300);
DISPLAY 1.021277 (-6425 1300);
DISPLAY INVISIBLE (-6425 1300);
FORCEPROP 1 LASTPIN (-6475 1200) $PN 1
J 0
(-6463 1212);
DISPLAY 0.489362 (-6463 1212);
PAINT MONO (-6463 1212);
FORCEPROP 1 LASTPIN (-6275 1200) $PN 2
J 0
(-6313 1212);
DISPLAY 0.489362 (-6313 1212);
PAINT MONO (-6313 1212);
FORCEPROP 1 LAST WATTAGE 1/16W
J 2
(-6000 1300);
DISPLAY 0.489362 (-6000 1300);
PAINT SKYBLUE (-6000 1300);
FORCEPROP 1 LAST PACK_TYPE 0402LF
J 0
(-6075 1200);
DISPLAY 0.489362 (-6075 1200);
PAINT SKYBLUE (-6075 1200);
FORCEPROP 1 LAST VALUE 1K
J 2
(-6200 1200);
DISPLAY 0.489362 (-6200 1200);
PAINT SKYBLUE (-6200 1200);
FORCEPROP 1 LAST TOLERANCE 1%
J 0
(-6175 1200);
DISPLAY 0.489362 (-6175 1200);
PAINT SKYBLUE (-6175 1200);
FORCEPROP 1 LAST MATERIAL CHIP
J 0
(-6250 1300);
DISPLAY 0.489362 (-6250 1300);
PAINT SKYBLUE (-6250 1300);
FORCEPROP 1 LAST PART_NUMBER CS21002FB06
J 0
(-6250 1250);
DISPLAY 0.489362 (-6250 1250);
PAINT SKYBLUE (-6250 1250);
DISPLAY INVISIBLE (-6250 1250);
FORCEPROP 1 LAST PATH I54
J 0
(-6425 1350);
DISPLAY 0.978723 (-6425 1350);
PAINT WHITE (-6425 1350);
DISPLAY INVISIBLE (-6425 1350);
FORCEPROP 2 LAST CDS_LIB pure_quanta
J 0
(-6375 1200);
DISPLAY INVISIBLE (-6375 1200);
FORCEADD Q_CAP..2
(-5575 1200);
FORCEPROP 1 LAST LOCATION C8072
J 1
(-5775 1200);
DISPLAY 0.489362 (-5775 1200);
PAINT SKYBLUE (-5775 1200);
FORCEPROP 0 LAST $SEC 1
J 0
(-5625 1300);
DISPLAY 0.680851 (-5625 1300);
PAINT MONO (-5625 1300);
DISPLAY INVISIBLE (-5625 1300);
FORCEPROP 0 LAST CDS_SEC 1
J 0
(-5625 1300);
DISPLAY 1.021277 (-5625 1300);
DISPLAY INVISIBLE (-5625 1300);
FORCEPROP 1 LASTPIN (-5675 1200) $PN 1
J 0
(-5685 1215);
DISPLAY 0.489362 (-5685 1215);
PAINT MONO (-5685 1215);
FORCEPROP 1 LASTPIN (-5475 1200) $PN 2
J 0
(-5490 1215);
DISPLAY 0.489362 (-5490 1215);
PAINT MONO (-5490 1215);
FORCEPROP 1 LAST PACK_TYPE 0402
J 1
(-5075 1150);
DISPLAY 0.489362 (-5075 1150);
PAINT SKYBLUE (-5075 1150);
FORCEPROP 1 LAST MATERIAL EMPTY
J 0
(-5100 1200);
DISPLAY 0.489362 (-5100 1200);
PAINT RED (-5100 1200);
FORCEPROP 1 LAST TOLERANCE 5%
J 2
(-4925 1150);
DISPLAY 0.489362 (-4925 1150);
PAINT SKYBLUE (-4925 1150);
FORCEPROP 1 LAST VOLTAGE 50V
J 0
(-5225 1200);
DISPLAY 0.489362 (-5225 1200);
PAINT SKYBLUE (-5225 1200);
FORCEPROP 1 LAST VALUE 1000PF
J 2
(-5250 1200);
DISPLAY 0.489362 (-5250 1200);
PAINT SKYBLUE (-5250 1200);
FORCEPROP 1 LAST PART_NUMBER TMP_QCH21006JB10
J 1
(-5300 1150);
DISPLAY 0.489362 (-5300 1150);
PAINT SKYBLUE (-5300 1150);
DISPLAY INVISIBLE (-5300 1150);
FORCEPROP 1 LAST PATH I55
J 0
(-5575 1400);
DISPLAY 0.978723 (-5575 1400);
PAINT WHITE (-5575 1400);
DISPLAY INVISIBLE (-5575 1400);
FORCEPROP 2 LAST CDS_LIB pure_quanta
J 0
(-5575 1200);
DISPLAY INVISIBLE (-5575 1200);
FORCEADD VCC_CORE..1
(-5975 2000);
FORCEPROP 3 LASTPIN (-5975 1950) SIG_NAME PVDD18_S5_P0\g
J 0
(-5965 1960);
DISPLAY 0.659574 (-5965 1960);
PAINT MONO (-5965 1960);
DISPLAY INVISIBLE (-5965 1960);
FORCEPROP 1 LAST HDL_POWER PVDD18_S5_P0
J 1
(-5975 2050);
DISPLAY 0.489362 (-5975 2050);
PAINT GREEN (-5975 2050);
FORCEPROP 1 LAST PATH I56
J 0
(-5925 2025);
DISPLAY 0.872340 (-5925 2025);
PAINT AQUA (-5925 2025);
DISPLAY INVISIBLE (-5925 2025);
FORCEPROP 2 LAST CDS_LIB pure_quanta_power
J 0
(-5975 2000);
DISPLAY INVISIBLE (-5975 2000);
FORCEADD UNIVERSAL_GND..1
(-5400 375);
FORCEPROP 3 LASTPIN (-5400 425) SIG_NAME GND\g
J 0
(-5390 435);
DISPLAY 0.659574 (-5390 435);
PAINT MONO (-5390 435);
DISPLAY INVISIBLE (-5390 435);
FORCEPROP 1 LAST PATH I57
J 0
(-5325 375);
DISPLAY 0.872340 (-5325 375);
PAINT AQUA (-5325 375);
DISPLAY INVISIBLE (-5325 375);
FORCEPROP 1 LAST HDL_POWER GND
J 1
(-5375 300);
DISPLAY 0.872340 (-5375 300);
PAINT GREEN (-5375 300);
DISPLAY INVISIBLE (-5375 300);
FORCEPROP 2 LAST CDS_LIB pure_quanta_power
J 0
(-5400 375);
DISPLAY INVISIBLE (-5400 375);
FORCEADD UNIVERSAL_GND..1
(-5075 375);
FORCEPROP 3 LASTPIN (-5075 425) SIG_NAME GND\g
J 0
(-5065 435);
DISPLAY 0.659574 (-5065 435);
PAINT MONO (-5065 435);
DISPLAY INVISIBLE (-5065 435);
FORCEPROP 1 LAST PATH I58
J 0
(-5000 375);
DISPLAY 0.872340 (-5000 375);
PAINT AQUA (-5000 375);
DISPLAY INVISIBLE (-5000 375);
FORCEPROP 1 LAST HDL_POWER GND
J 1
(-5050 300);
DISPLAY 0.872340 (-5050 300);
PAINT GREEN (-5050 300);
DISPLAY INVISIBLE (-5050 300);
FORCEPROP 2 LAST CDS_LIB pure_quanta_power
J 0
(-5075 375);
PAINT MONO (-5075 375);
DISPLAY INVISIBLE (-5075 375);
FORCEADD Q_RES..2
(-5400 575);
FORCEPROP 1 LAST LOCATION PR600
J 0
(-5350 700);
DISPLAY 0.489362 (-5350 700);
PAINT SKYBLUE (-5350 700);
FORCEPROP 0 LAST $SEC 1
J 0
(-5350 725);
DISPLAY 0.680851 (-5350 725);
PAINT MONO (-5350 725);
DISPLAY INVISIBLE (-5350 725);
FORCEPROP 0 LAST CDS_SEC 1
J 0
(-5350 725);
DISPLAY 0.680851 (-5350 725);
DISPLAY INVISIBLE (-5350 725);
FORCEPROP 1 LASTPIN (-5400 675) $PN 1
J 0
(-5395 637);
DISPLAY 0.787234 (-5395 637);
PAINT MONO (-5395 637);
DISPLAY INVISIBLE (-5395 637);
FORCEPROP 1 LASTPIN (-5400 475) $PN 2
J 0
(-5395 485);
DISPLAY 0.787234 (-5395 485);
PAINT MONO (-5395 485);
DISPLAY INVISIBLE (-5395 485);
FORCEPROP 1 LAST WATTAGE 1/16W
J 0
(-5350 550);
DISPLAY 0.489362 (-5350 550);
PAINT SKYBLUE (-5350 550);
FORCEPROP 1 LAST PACK_TYPE 0402LF
J 0
(-5350 400);
DISPLAY 0.489362 (-5350 400);
PAINT SKYBLUE (-5350 400);
FORCEPROP 1 LAST VALUE 4.99K
J 0
(-5350 650);
DISPLAY 0.489362 (-5350 650);
PAINT SKYBLUE (-5350 650);
FORCEPROP 1 LAST TOLERANCE 1%
J 0
(-5350 600);
DISPLAY 0.489362 (-5350 600);
PAINT SKYBLUE (-5350 600);
FORCEPROP 1 LAST MATERIAL EMPTY
J 0
(-5350 500);
DISPLAY 0.489362 (-5350 500);
PAINT RED (-5350 500);
FORCEPROP 1 LAST PART_NUMBER CS24992FB07
J 0
(-5350 450);
DISPLAY 0.489362 (-5350 450);
PAINT SKYBLUE (-5350 450);
DISPLAY INVISIBLE (-5350 450);
FORCEPROP 1 LAST PATH I59
J 0
(-5350 750);
DISPLAY 0.978723 (-5350 750);
PAINT WHITE (-5350 750);
DISPLAY INVISIBLE (-5350 750);
FORCEPROP 2 LAST CDS_LIB pure_quanta
J 0
(-5400 575);
DISPLAY INVISIBLE (-5400 575);
FORCEADD MOSFET_N..1
(-7650 1750);
FORCEPROP 1 LAST LOCATION PQ14
J 0
(-7525 1775);
DISPLAY 0.489362 (-7525 1775);
PAINT SKYBLUE (-7525 1775);
FORCEPROP 0 LAST $SEC 1
J 0
(-7500 1800);
DISPLAY 0.680851 (-7500 1800);
PAINT MONO (-7500 1800);
DISPLAY INVISIBLE (-7500 1800);
FORCEPROP 0 LAST CDS_SEC 1
J 0
(-7500 1800);
DISPLAY 1.021277 (-7500 1800);
DISPLAY INVISIBLE (-7500 1800);
FORCEPROP 1 LASTPIN (-7600 1850) $PN D
R 1
J 0
(-7600 1843);
DISPLAY 0.489362 (-7600 1843);
PAINT MONO (-7600 1843);
FORCEPROP 1 LASTPIN (-7750 1650) $PN G
J 2
(-7740 1653);
DISPLAY 0.489362 (-7740 1653);
PAINT MONO (-7740 1653);
FORCEPROP 1 LASTPIN (-7600 1550) $PN S
R 1
J 2
(-7600 1563);
DISPLAY 0.489362 (-7600 1563);
PAINT MONO (-7600 1563);
FORCEPROP 1 LAST VALUE BSS138K
J 0
(-7525 1725);
DISPLAY 0.489362 (-7525 1725);
PAINT SKYBLUE (-7525 1725);
FORCEPROP 1 LAST MATERIAL IC
J 0
(-7525 1625);
DISPLAY 0.489362 (-7525 1625);
PAINT SKYBLUE (-7525 1625);
FORCEPROP 2 LAST PATH I6
J 0
(-7525 1800);
DISPLAY 0.680851 (-7525 1800);
FORCEPROP 1 LAST PART_NUMBER BAM138K0000
J 0
(-7525 1675);
DISPLAY 0.489362 (-7525 1675);
PAINT SKYBLUE (-7525 1675);
DISPLAY INVISIBLE (-7525 1675);
FORCEPROP 0 LAST MANUF_PN BSS138K
J 0
(-7475 1625);
DISPLAY 1.021277 (-7475 1625);
DISPLAY INVISIBLE (-7475 1625);
FORCEPROP 2 LAST CDS_LIB pure_quanta
J 0
(-7650 1750);
DISPLAY INVISIBLE (-7650 1750);
FORCEPROP 1 LAST CDS_LMAN_SYM_OUTLINE -50,50,100,-150
J 0
(-7650 1750);
DISPLAY 0.468085 (-7650 1750);
PAINT GREEN (-7650 1750);
DISPLAY INVISIBLE (-7650 1750);
FORCEPROP 1 LAST PACK_TYPE SMLF
J 0
(-7625 1500);
DISPLAY 0.723404 (-7625 1500);
PAINT SKYBLUE (-7625 1500);
DISPLAY INVISIBLE (-7625 1500);
FORCEADD Q_CAP..1
(-5075 575);
FORCEPROP 1 LAST LOCATION PC74
J 0
(-5025 700);
DISPLAY 0.489362 (-5025 700);
PAINT SKYBLUE (-5025 700);
FORCEPROP 0 LAST $SEC 1
J 0
(-5025 750);
DISPLAY 0.680851 (-5025 750);
PAINT MONO (-5025 750);
DISPLAY INVISIBLE (-5025 750);
FORCEPROP 0 LAST CDS_SEC 1
J 0
(-5025 750);
DISPLAY 1.021277 (-5025 750);
DISPLAY INVISIBLE (-5025 750);
FORCEPROP 1 LASTPIN (-5075 675) $PN 1
J 0
(-5065 655);
DISPLAY 0.489362 (-5065 655);
PAINT MONO (-5065 655);
FORCEPROP 1 LASTPIN (-5075 475) $PN 2
J 0
(-5065 455);
DISPLAY 0.489362 (-5065 455);
PAINT MONO (-5065 455);
FORCEPROP 1 LAST TOLERANCE 10%
J 0
(-5025 550);
DISPLAY 0.489362 (-5025 550);
PAINT SKYBLUE (-5025 550);
FORCEPROP 1 LAST MATERIAL X7R
J 0
(-5025 500);
DISPLAY 0.489362 (-5025 500);
PAINT SKYBLUE (-5025 500);
FORCEPROP 1 LAST VOLTAGE 25V
J 0
(-5025 600);
DISPLAY 0.489362 (-5025 600);
PAINT SKYBLUE (-5025 600);
FORCEPROP 1 LAST VALUE 0.1UF
J 0
(-5025 650);
DISPLAY 0.489362 (-5025 650);
PAINT SKYBLUE (-5025 650);
FORCEPROP 1 LAST PACK_TYPE 0402
J 0
(-5025 450);
DISPLAY 0.489362 (-5025 450);
PAINT SKYBLUE (-5025 450);
FORCEPROP 1 LAST PART_NUMBER CH4104K1B00
J 0
(-5025 400);
DISPLAY 0.489362 (-5025 400);
PAINT SKYBLUE (-5025 400);
DISPLAY INVISIBLE (-5025 400);
FORCEPROP 1 LAST PATH I60
J 0
(-5025 725);
DISPLAY 0.978723 (-5025 725);
PAINT WHITE (-5025 725);
DISPLAY INVISIBLE (-5025 725);
FORCEPROP 2 LAST CDS_LIB pure_quanta
J 0
(-5075 575);
DISPLAY INVISIBLE (-5075 575);
FORCEADD UNIVERSAL_GND..1
(-4850 625);
FORCEPROP 3 LASTPIN (-4850 675) SIG_NAME GND\g
J 0
(-4840 685);
DISPLAY 0.659574 (-4840 685);
PAINT MONO (-4840 685);
DISPLAY INVISIBLE (-4840 685);
FORCEPROP 1 LAST HDL_POWER GND
J 1
(-4825 550);
DISPLAY 0.872340 (-4825 550);
PAINT GREEN (-4825 550);
DISPLAY INVISIBLE (-4825 550);
FORCEPROP 2 LAST CDS_LIB pure_quanta_power
J 0
(-4850 625);
PAINT MONO (-4850 625);
DISPLAY INVISIBLE (-4850 625);
FORCEPROP 1 LAST PATH I61
J 0
(-4775 625);
DISPLAY 0.872340 (-4775 625);
PAINT AQUA (-4775 625);
DISPLAY INVISIBLE (-4775 625);
FORCEADD UNIVERSAL_GND..1
R 1
(-5025 1925);
FORCEPROP 3 LASTPIN (-5075 1925) SIG_NAME GND\g
J 0
(-5065 1935);
DISPLAY 0.659574 (-5065 1935);
PAINT MONO (-5065 1935);
DISPLAY INVISIBLE (-5065 1935);
FORCEPROP 1 LAST PATH I62
R 1
J 0
(-5025 2000);
DISPLAY 0.872340 (-5025 2000);
PAINT AQUA (-5025 2000);
DISPLAY INVISIBLE (-5025 2000);
FORCEPROP 1 LAST HDL_POWER GND
R 1
J 1
(-4950 1950);
DISPLAY 0.872340 (-4950 1950);
PAINT GREEN (-4950 1950);
DISPLAY INVISIBLE (-4950 1950);
FORCEPROP 2 LAST CDS_LIB pure_quanta_power
J 0
(-5025 1925);
DISPLAY INVISIBLE (-5025 1925);
FORCEADD Q_CAP..2
(-5425 1925);
FORCEPROP 1 LAST LOCATION PC73
J 1
(-5750 1975);
DISPLAY 0.489362 (-5750 1975);
PAINT SKYBLUE (-5750 1975);
FORCEPROP 0 LAST $SEC 1
J 0
(-4850 2000);
DISPLAY 0.680851 (-4850 2000);
PAINT MONO (-4850 2000);
DISPLAY INVISIBLE (-4850 2000);
FORCEPROP 0 LAST CDS_SEC 1
J 0
(-4850 2000);
DISPLAY 1.021277 (-4850 2000);
DISPLAY INVISIBLE (-4850 2000);
FORCEPROP 1 LASTPIN (-5525 1925) $PN 1
J 0
(-5535 1940);
DISPLAY 0.489362 (-5535 1940);
PAINT MONO (-5535 1940);
FORCEPROP 1 LASTPIN (-5325 1925) $PN 2
J 0
(-5340 1940);
DISPLAY 0.489362 (-5340 1940);
PAINT MONO (-5340 1940);
FORCEPROP 1 LAST VALUE 1UF
J 2
(-5625 1975);
DISPLAY 0.489362 (-5625 1975);
PAINT SKYBLUE (-5625 1975);
FORCEPROP 1 LAST TOLERANCE 10%
J 2
(-4850 1975);
DISPLAY 0.489362 (-4850 1975);
PAINT SKYBLUE (-4850 1975);
FORCEPROP 1 LAST PACK_TYPE 0402
J 1
(-5000 1975);
DISPLAY 0.489362 (-5000 1975);
PAINT SKYBLUE (-5000 1975);
FORCEPROP 1 LAST MATERIAL X7R
J 0
(-5450 1975);
DISPLAY 0.489362 (-5450 1975);
PAINT SKYBLUE (-5450 1975);
FORCEPROP 1 LAST VOLTAGE 6.3V
J 0
(-5575 1975);
DISPLAY 0.489362 (-5575 1975);
PAINT SKYBLUE (-5575 1975);
FORCEPROP 1 LAST PART_NUMBER CH5101K1B01
J 1
(-5200 1975);
DISPLAY 0.489362 (-5200 1975);
PAINT SKYBLUE (-5200 1975);
DISPLAY INVISIBLE (-5200 1975);
FORCEPROP 1 LAST PATH I63
J 0
(-5425 2125);
DISPLAY 0.978723 (-5425 2125);
PAINT WHITE (-5425 2125);
DISPLAY INVISIBLE (-5425 2125);
FORCEPROP 2 LAST CDS_LIB pure_quanta
J 0
(-5425 1925);
DISPLAY INVISIBLE (-5425 1925);
FORCEADD UNIVERSAL_GND..1
R 1
(-4875 1200);
FORCEPROP 3 LASTPIN (-4925 1200) SIG_NAME GND\g
J 0
(-4915 1210);
DISPLAY 0.659574 (-4915 1210);
PAINT MONO (-4915 1210);
DISPLAY INVISIBLE (-4915 1210);
FORCEPROP 1 LAST PATH I64
R 1
J 0
(-4875 1275);
DISPLAY 0.872340 (-4875 1275);
PAINT AQUA (-4875 1275);
DISPLAY INVISIBLE (-4875 1275);
FORCEPROP 1 LAST HDL_POWER GND
R 1
J 1
(-4800 1225);
DISPLAY 0.872340 (-4800 1225);
PAINT GREEN (-4800 1225);
DISPLAY INVISIBLE (-4800 1225);
FORCEPROP 2 LAST CDS_LIB pure_quanta_power
J 0
(-4875 1200);
PAINT MONO (-4875 1200);
DISPLAY INVISIBLE (-4875 1200);
FORCEADD VCC_CORE..1
(-6325 2725);
FORCEPROP 3 LASTPIN (-6325 2675) SIG_NAME PVDD18_S5_P0\g
J 0
(-6315 2685);
DISPLAY 0.659574 (-6315 2685);
PAINT MONO (-6315 2685);
DISPLAY INVISIBLE (-6315 2685);
FORCEPROP 1 LAST HDL_POWER PVDD18_S5_P0
J 1
(-6325 2775);
DISPLAY 0.489362 (-6325 2775);
PAINT GREEN (-6325 2775);
FORCEPROP 1 LAST PATH I65
J 0
(-6275 2750);
DISPLAY 0.872340 (-6275 2750);
PAINT AQUA (-6275 2750);
DISPLAY INVISIBLE (-6275 2750);
FORCEPROP 2 LAST CDS_LIB pure_quanta_power
J 0
(-6325 2725);
DISPLAY INVISIBLE (-6325 2725);
FORCEADD Q_RES..1
(-5725 2300);
FORCEPROP 1 LAST LOCATION R8064
J 0
(-5775 2350);
DISPLAY 0.489362 (-5775 2350);
PAINT SKYBLUE (-5775 2350);
FORCEPROP 0 LAST $SEC 1
J 0
(-5775 2375);
DISPLAY 0.680851 (-5775 2375);
PAINT MONO (-5775 2375);
DISPLAY INVISIBLE (-5775 2375);
FORCEPROP 0 LAST CDS_SEC 1
J 0
(-5775 2375);
DISPLAY 1.021277 (-5775 2375);
DISPLAY INVISIBLE (-5775 2375);
FORCEPROP 1 LASTPIN (-5825 2300) $PN 1
J 0
(-5813 2312);
DISPLAY 0.489362 (-5813 2312);
PAINT MONO (-5813 2312);
FORCEPROP 1 LASTPIN (-5625 2300) $PN 2
J 0
(-5663 2312);
DISPLAY 0.489362 (-5663 2312);
PAINT MONO (-5663 2312);
FORCEPROP 1 LAST MATERIAL CHIP
J 0
(-6050 2250);
DISPLAY 0.489362 (-6050 2250);
PAINT SKYBLUE (-6050 2250);
FORCEPROP 1 LAST VALUE 0
J 2
(-5725 2250);
DISPLAY 0.489362 (-5725 2250);
PAINT SKYBLUE (-5725 2250);
FORCEPROP 1 LAST TOLERANCE 5%
J 0
(-5700 2250);
DISPLAY 0.489362 (-5700 2250);
PAINT SKYBLUE (-5700 2250);
FORCEPROP 1 LAST PACK_TYPE 0402LF
J 0
(-5625 2250);
DISPLAY 0.489362 (-5625 2250);
PAINT SKYBLUE (-5625 2250);
FORCEPROP 1 LAST WATTAGE 1/16W
J 2
(-5800 2250);
DISPLAY 0.489362 (-5800 2250);
PAINT SKYBLUE (-5800 2250);
FORCEPROP 1 LAST PART_NUMBER CS00002JB13
J 0
(-6400 2250);
DISPLAY 0.489362 (-6400 2250);
PAINT SKYBLUE (-6400 2250);
DISPLAY INVISIBLE (-6400 2250);
FORCEPROP 1 LAST PATH I66
J 0
(-5775 2450);
DISPLAY 0.978723 (-5775 2450);
PAINT WHITE (-5775 2450);
DISPLAY INVISIBLE (-5775 2450);
FORCEPROP 2 LAST CDS_LIB pure_quanta
J 0
(-5725 2300);
DISPLAY INVISIBLE (-5725 2300);
FORCEADD Q_RES..1
(-5725 2450);
FORCEPROP 1 LAST LOCATION R8063
J 0
(-5775 2500);
DISPLAY 0.489362 (-5775 2500);
PAINT SKYBLUE (-5775 2500);
FORCEPROP 0 LAST $SEC 1
J 0
(-5775 2525);
DISPLAY 0.680851 (-5775 2525);
PAINT MONO (-5775 2525);
DISPLAY INVISIBLE (-5775 2525);
FORCEPROP 0 LAST CDS_SEC 1
J 0
(-5775 2525);
DISPLAY 1.021277 (-5775 2525);
DISPLAY INVISIBLE (-5775 2525);
FORCEPROP 1 LASTPIN (-5825 2450) $PN 1
J 0
(-5813 2462);
DISPLAY 0.489362 (-5813 2462);
PAINT MONO (-5813 2462);
FORCEPROP 1 LASTPIN (-5625 2450) $PN 2
J 0
(-5663 2462);
DISPLAY 0.489362 (-5663 2462);
PAINT MONO (-5663 2462);
FORCEPROP 1 LAST VALUE 100
J 2
(-5650 2400);
DISPLAY 0.489362 (-5650 2400);
PAINT SKYBLUE (-5650 2400);
FORCEPROP 1 LAST WATTAGE 1/16W
J 2
(-5800 2400);
DISPLAY 0.489362 (-5800 2400);
PAINT SKYBLUE (-5800 2400);
FORCEPROP 1 LAST PACK_TYPE 0402LF
J 0
(-5525 2400);
DISPLAY 0.489362 (-5525 2400);
PAINT SKYBLUE (-5525 2400);
FORCEPROP 1 LAST TOLERANCE 1%
J 0
(-5600 2400);
DISPLAY 0.489362 (-5600 2400);
PAINT SKYBLUE (-5600 2400);
FORCEPROP 1 LAST MATERIAL CHIP
J 0
(-6050 2400);
DISPLAY 0.489362 (-6050 2400);
PAINT SKYBLUE (-6050 2400);
FORCEPROP 1 LAST PART_NUMBER CS11002FB07
J 0
(-6400 2400);
DISPLAY 0.489362 (-6400 2400);
PAINT SKYBLUE (-6400 2400);
DISPLAY INVISIBLE (-6400 2400);
FORCEPROP 1 LAST PATH I67
J 0
(-5775 2600);
DISPLAY 0.978723 (-5775 2600);
PAINT WHITE (-5775 2600);
DISPLAY INVISIBLE (-5775 2600);
FORCEPROP 2 LAST CDS_LIB pure_quanta
J 0
(-5725 2450);
DISPLAY INVISIBLE (-5725 2450);
FORCEADD Q_RES..1
(-5875 2600);
FORCEPROP 1 LAST LOCATION R8070
J 0
(-6250 2625);
DISPLAY 0.489362 (-6250 2625);
PAINT SKYBLUE (-6250 2625);
FORCEPROP 0 LAST $SEC 1
J 0
(-6125 2700);
DISPLAY 0.680851 (-6125 2700);
PAINT MONO (-6125 2700);
DISPLAY INVISIBLE (-6125 2700);
FORCEPROP 0 LAST CDS_SEC 1
J 0
(-6125 2700);
DISPLAY 1.021277 (-6125 2700);
DISPLAY INVISIBLE (-6125 2700);
FORCEPROP 1 LASTPIN (-5975 2600) $PN 1
J 0
(-5963 2612);
DISPLAY 0.489362 (-5963 2612);
PAINT MONO (-5963 2612);
FORCEPROP 1 LASTPIN (-5775 2600) $PN 2
J 0
(-5813 2612);
DISPLAY 0.489362 (-5813 2612);
PAINT MONO (-5813 2612);
FORCEPROP 1 LAST VALUE 1K
J 2
(-6075 2625);
DISPLAY 0.489362 (-6075 2625);
PAINT SKYBLUE (-6075 2625);
FORCEPROP 1 LAST TOLERANCE 1%
J 0
(-6050 2625);
DISPLAY 0.489362 (-6050 2625);
PAINT SKYBLUE (-6050 2625);
FORCEPROP 1 LAST WATTAGE 1/16W
J 2
(-5600 2625);
DISPLAY 0.489362 (-5600 2625);
PAINT SKYBLUE (-5600 2625);
FORCEPROP 1 LAST PACK_TYPE 0402LF
J 0
(-5950 2550);
DISPLAY 0.489362 (-5950 2550);
PAINT SKYBLUE (-5950 2550);
FORCEPROP 1 LAST MATERIAL CHIP
J 0
(-6050 2550);
DISPLAY 0.489362 (-6050 2550);
PAINT SKYBLUE (-6050 2550);
FORCEPROP 1 LAST PART_NUMBER CS21002FB06
J 0
(-6125 2675);
DISPLAY 0.489362 (-6125 2675);
PAINT SKYBLUE (-6125 2675);
DISPLAY INVISIBLE (-6125 2675);
FORCEPROP 1 LAST PATH I68
J 0
(-5925 2750);
DISPLAY 0.978723 (-5925 2750);
PAINT WHITE (-5925 2750);
DISPLAY INVISIBLE (-5925 2750);
FORCEPROP 2 LAST CDS_LIB pure_quanta
J 0
(-5875 2600);
DISPLAY INVISIBLE (-5875 2600);
FORCEADD Q_CAP..1
(-5625 3025);
FORCEPROP 1 LAST LOCATION PC71
J 0
(-5575 3150);
DISPLAY 0.489362 (-5575 3150);
PAINT SKYBLUE (-5575 3150);
FORCEPROP 0 LAST $SEC 1
J 0
(-5575 3150);
DISPLAY 0.680851 (-5575 3150);
PAINT MONO (-5575 3150);
DISPLAY INVISIBLE (-5575 3150);
FORCEPROP 0 LAST CDS_SEC 1
J 0
(-5575 3150);
DISPLAY 1.021277 (-5575 3150);
DISPLAY INVISIBLE (-5575 3150);
FORCEPROP 1 LASTPIN (-5625 3125) $PN 1
J 0
(-5615 3105);
DISPLAY 0.489362 (-5615 3105);
PAINT MONO (-5615 3105);
FORCEPROP 1 LASTPIN (-5625 2925) $PN 2
J 0
(-5615 2905);
DISPLAY 0.489362 (-5615 2905);
PAINT MONO (-5615 2905);
FORCEPROP 1 LAST MATERIAL X7R
J 0
(-5575 2950);
DISPLAY 0.489362 (-5575 2950);
PAINT SKYBLUE (-5575 2950);
FORCEPROP 1 LAST PACK_TYPE 0402
J 0
(-5575 2900);
DISPLAY 0.489362 (-5575 2900);
PAINT SKYBLUE (-5575 2900);
FORCEPROP 1 LAST VOLTAGE 50V
J 0
(-5575 3050);
DISPLAY 0.489362 (-5575 3050);
PAINT SKYBLUE (-5575 3050);
FORCEPROP 1 LAST VALUE 3300PF
J 0
(-5575 3100);
DISPLAY 0.489362 (-5575 3100);
PAINT SKYBLUE (-5575 3100);
FORCEPROP 1 LAST TOLERANCE 10%
J 0
(-5575 3000);
DISPLAY 0.489362 (-5575 3000);
PAINT SKYBLUE (-5575 3000);
FORCEPROP 1 LAST PART_NUMBER TMP_QCH2336K1B12
J 0
(-5575 2850);
DISPLAY 0.489362 (-5575 2850);
PAINT SKYBLUE (-5575 2850);
DISPLAY INVISIBLE (-5575 2850);
FORCEPROP 1 LAST PATH I69
J 0
(-5575 3175);
DISPLAY 0.978723 (-5575 3175);
PAINT WHITE (-5575 3175);
DISPLAY INVISIBLE (-5575 3175);
FORCEPROP 2 LAST CDS_LIB pure_quanta
J 0
(-5625 3025);
DISPLAY INVISIBLE (-5625 3025);
FORCEADD UNIVERSAL_GND..1
(-7600 1375);
FORCEPROP 3 LASTPIN (-7600 1425) SIG_NAME GND\g
J 0
(-7590 1435);
DISPLAY 0.659574 (-7590 1435);
PAINT MONO (-7590 1435);
DISPLAY INVISIBLE (-7590 1435);
FORCEPROP 1 LAST PATH I7
J 0
(-7525 1375);
DISPLAY 0.872340 (-7525 1375);
PAINT AQUA (-7525 1375);
DISPLAY INVISIBLE (-7525 1375);
FORCEPROP 1 LAST HDL_POWER GND
J 1
(-7575 1300);
DISPLAY 0.872340 (-7575 1300);
PAINT GREEN (-7575 1300);
DISPLAY INVISIBLE (-7575 1300);
FORCEPROP 2 LAST CDS_LIB pure_quanta_power
J 0
(-7600 1375);
DISPLAY INVISIBLE (-7600 1375);
FORCEADD Q_RES..1
(-6075 3200);
FORCEPROP 1 LAST LOCATION PR69
J 0
(-6275 3200);
DISPLAY 0.489362 (-6275 3200);
PAINT SKYBLUE (-6275 3200);
FORCEPROP 0 LAST $SEC 1
J 0
(-6125 3300);
DISPLAY 0.680851 (-6125 3300);
PAINT MONO (-6125 3300);
DISPLAY INVISIBLE (-6125 3300);
FORCEPROP 0 LAST CDS_SEC 1
J 0
(-6125 3300);
DISPLAY 1.021277 (-6125 3300);
DISPLAY INVISIBLE (-6125 3300);
FORCEPROP 1 LASTPIN (-6175 3200) $PN 1
J 0
(-6163 3212);
DISPLAY 0.489362 (-6163 3212);
PAINT MONO (-6163 3212);
FORCEPROP 1 LASTPIN (-5975 3200) $PN 2
J 0
(-6013 3212);
DISPLAY 0.489362 (-6013 3212);
PAINT MONO (-6013 3212);
FORCEPROP 1 LAST PACK_TYPE 0402LF
J 0
(-5825 3200);
DISPLAY 0.489362 (-5825 3200);
PAINT SKYBLUE (-5825 3200);
FORCEPROP 1 LAST MATERIAL CHIP
J 0
(-5950 3300);
DISPLAY 0.489362 (-5950 3300);
PAINT SKYBLUE (-5950 3300);
FORCEPROP 1 LAST WATTAGE 1/16W
J 2
(-5700 3300);
DISPLAY 0.489362 (-5700 3300);
PAINT SKYBLUE (-5700 3300);
FORCEPROP 1 LAST TOLERANCE 5%
J 0
(-5900 3200);
DISPLAY 0.489362 (-5900 3200);
PAINT SKYBLUE (-5900 3200);
FORCEPROP 1 LAST VALUE 0
J 2
(-5925 3200);
DISPLAY 0.489362 (-5925 3200);
PAINT SKYBLUE (-5925 3200);
FORCEPROP 1 LAST PART_NUMBER CS00002JB13
J 0
(-5950 3250);
DISPLAY 0.489362 (-5950 3250);
PAINT SKYBLUE (-5950 3250);
DISPLAY INVISIBLE (-5950 3250);
FORCEPROP 1 LAST PATH I70
J 0
(-6125 3350);
DISPLAY 0.978723 (-6125 3350);
PAINT WHITE (-6125 3350);
DISPLAY INVISIBLE (-6125 3350);
FORCEPROP 2 LAST CDS_LIB pure_quanta
J 0
(-6075 3200);
DISPLAY INVISIBLE (-6075 3200);
FORCEADD Q_RES..1
(-5175 2175);
FORCEPROP 1 LAST LOCATION R8075
J 0
(-5225 2125);
DISPLAY 0.489362 (-5225 2125);
PAINT SKYBLUE (-5225 2125);
FORCEPROP 0 LAST $SEC 1
J 0
(-5425 2275);
DISPLAY 0.680851 (-5425 2275);
PAINT MONO (-5425 2275);
DISPLAY INVISIBLE (-5425 2275);
FORCEPROP 0 LAST CDS_SEC 1
J 0
(-5425 2275);
DISPLAY 1.021277 (-5425 2275);
DISPLAY INVISIBLE (-5425 2275);
FORCEPROP 1 LASTPIN (-5275 2175) $PN 1
J 0
(-5263 2187);
DISPLAY 0.489362 (-5263 2187);
PAINT MONO (-5263 2187);
FORCEPROP 1 LASTPIN (-5075 2175) $PN 2
J 0
(-5113 2187);
DISPLAY 0.489362 (-5113 2187);
PAINT MONO (-5113 2187);
FORCEPROP 1 LAST WATTAGE 1/16W
J 2
(-4900 2200);
DISPLAY 0.489362 (-4900 2200);
PAINT SKYBLUE (-4900 2200);
FORCEPROP 1 LAST PACK_TYPE 0402LF
J 0
(-5275 2200);
DISPLAY 0.489362 (-5275 2200);
PAINT SKYBLUE (-5275 2200);
FORCEPROP 1 LAST VALUE 1K
J 2
(-5375 2200);
DISPLAY 0.489362 (-5375 2200);
PAINT SKYBLUE (-5375 2200);
FORCEPROP 1 LAST TOLERANCE 1%
J 0
(-5350 2200);
DISPLAY 0.489362 (-5350 2200);
PAINT SKYBLUE (-5350 2200);
FORCEPROP 1 LAST MATERIAL CHIP
J 0
(-5125 2200);
DISPLAY 0.489362 (-5125 2200);
PAINT SKYBLUE (-5125 2200);
FORCEPROP 1 LAST PART_NUMBER CS21002FB06
J 0
(-5425 2250);
DISPLAY 0.489362 (-5425 2250);
PAINT SKYBLUE (-5425 2250);
DISPLAY INVISIBLE (-5425 2250);
FORCEPROP 2 LAST CDS_LIB pure_quanta
J 0
(-5175 2175);
DISPLAY INVISIBLE (-5175 2175);
FORCEPROP 1 LAST PATH I71
J 0
(-5225 2325);
DISPLAY 0.978723 (-5225 2325);
PAINT WHITE (-5225 2325);
DISPLAY INVISIBLE (-5225 2325);
FORCEADD UNIVERSAL_GND..1
(-2750 675);
FORCEPROP 3 LASTPIN (-2750 725) SIG_NAME GND\g
J 0
(-2740 735);
DISPLAY 0.659574 (-2740 735);
PAINT MONO (-2740 735);
DISPLAY INVISIBLE (-2740 735);
FORCEPROP 1 LAST PATH I72
J 0
(-2675 675);
DISPLAY 0.872340 (-2675 675);
PAINT AQUA (-2675 675);
DISPLAY INVISIBLE (-2675 675);
FORCEPROP 1 LAST HDL_POWER GND
J 1
(-2725 600);
DISPLAY 0.872340 (-2725 600);
PAINT GREEN (-2725 600);
DISPLAY INVISIBLE (-2725 600);
FORCEPROP 2 LAST CDS_LIB pure_quanta_power
J 0
(-2750 675);
PAINT MONO (-2750 675);
DISPLAY INVISIBLE (-2750 675);
FORCEADD Q_CAP..1
(-2750 925);
FORCEPROP 1 LAST LOCATION PC78
J 0
(-2700 1025);
DISPLAY 0.489362 (-2700 1025);
PAINT SKYBLUE (-2700 1025);
FORCEPROP 0 LAST $SEC 1
J 0
(-2700 1075);
DISPLAY 0.680851 (-2700 1075);
PAINT MONO (-2700 1075);
DISPLAY INVISIBLE (-2700 1075);
FORCEPROP 0 LAST CDS_SEC 1
J 0
(-2700 1075);
DISPLAY 1.021277 (-2700 1075);
DISPLAY INVISIBLE (-2700 1075);
FORCEPROP 1 LASTPIN (-2750 1025) $PN 1
J 0
(-2740 1005);
DISPLAY 0.489362 (-2740 1005);
PAINT MONO (-2740 1005);
FORCEPROP 1 LASTPIN (-2750 825) $PN 2
J 0
(-2740 805);
DISPLAY 0.489362 (-2740 805);
PAINT MONO (-2740 805);
FORCEPROP 1 LAST MATERIAL X7R
J 0
(-2700 825);
DISPLAY 0.489362 (-2700 825);
PAINT SKYBLUE (-2700 825);
FORCEPROP 1 LAST TOLERANCE 10%
J 0
(-2700 875);
DISPLAY 0.489362 (-2700 875);
PAINT SKYBLUE (-2700 875);
FORCEPROP 1 LAST VOLTAGE 50V
J 0
(-2700 925);
DISPLAY 0.489362 (-2700 925);
PAINT SKYBLUE (-2700 925);
FORCEPROP 1 LAST PACK_TYPE 0402
J 0
(-2700 775);
DISPLAY 0.489362 (-2700 775);
PAINT SKYBLUE (-2700 775);
FORCEPROP 1 LAST VALUE 470PF
J 0
(-2700 975);
DISPLAY 0.489362 (-2700 975);
PAINT SKYBLUE (-2700 975);
FORCEPROP 1 LAST PART_NUMBER TMP_QCH14706KB18
J 0
(-2700 700);
DISPLAY 0.489362 (-2700 700);
PAINT SKYBLUE (-2700 700);
DISPLAY INVISIBLE (-2700 700);
FORCEPROP 1 LAST PATH I73
J 0
(-2700 1075);
DISPLAY 0.978723 (-2700 1075);
PAINT WHITE (-2700 1075);
DISPLAY INVISIBLE (-2700 1075);
FORCEPROP 2 LAST CDS_LIB pure_quanta
J 0
(-2750 925);
DISPLAY INVISIBLE (-2750 925);
FORCEADD UNIVERSAL_GND..1
(-2750 1250);
FORCEPROP 3 LASTPIN (-2750 1300) SIG_NAME GND\g
J 0
(-2740 1310);
DISPLAY 0.659574 (-2740 1310);
PAINT MONO (-2740 1310);
DISPLAY INVISIBLE (-2740 1310);
FORCEPROP 1 LAST PATH I74
J 0
(-2675 1250);
DISPLAY 0.872340 (-2675 1250);
PAINT AQUA (-2675 1250);
DISPLAY INVISIBLE (-2675 1250);
FORCEPROP 1 LAST HDL_POWER GND
J 1
(-2725 1175);
DISPLAY 0.872340 (-2725 1175);
PAINT GREEN (-2725 1175);
DISPLAY INVISIBLE (-2725 1175);
FORCEPROP 2 LAST CDS_LIB pure_quanta_power
J 0
(-2750 1250);
DISPLAY INVISIBLE (-2750 1250);
FORCEADD Q_CAP..1
(-2750 1500);
FORCEPROP 1 LAST LOCATION PC77
J 0
(-2700 1600);
DISPLAY 0.489362 (-2700 1600);
PAINT SKYBLUE (-2700 1600);
FORCEPROP 0 LAST $SEC 1
J 0
(-2700 1625);
DISPLAY 0.680851 (-2700 1625);
PAINT MONO (-2700 1625);
DISPLAY INVISIBLE (-2700 1625);
FORCEPROP 0 LAST CDS_SEC 1
J 0
(-2700 1625);
DISPLAY 1.021277 (-2700 1625);
DISPLAY INVISIBLE (-2700 1625);
FORCEPROP 1 LASTPIN (-2750 1600) $PN 1
J 0
(-2740 1580);
DISPLAY 0.489362 (-2740 1580);
PAINT MONO (-2740 1580);
FORCEPROP 1 LASTPIN (-2750 1400) $PN 2
J 0
(-2740 1380);
DISPLAY 0.489362 (-2740 1380);
PAINT MONO (-2740 1380);
FORCEPROP 1 LAST MATERIAL X7R
J 0
(-2700 1400);
DISPLAY 0.489362 (-2700 1400);
PAINT SKYBLUE (-2700 1400);
FORCEPROP 1 LAST TOLERANCE 10%
J 0
(-2700 1450);
DISPLAY 0.489362 (-2700 1450);
PAINT SKYBLUE (-2700 1450);
FORCEPROP 1 LAST VALUE 470PF
J 0
(-2700 1550);
DISPLAY 0.489362 (-2700 1550);
PAINT SKYBLUE (-2700 1550);
FORCEPROP 1 LAST VOLTAGE 50V
J 0
(-2700 1500);
DISPLAY 0.489362 (-2700 1500);
PAINT SKYBLUE (-2700 1500);
FORCEPROP 1 LAST PACK_TYPE 0402
J 0
(-2700 1350);
DISPLAY 0.489362 (-2700 1350);
PAINT SKYBLUE (-2700 1350);
FORCEPROP 1 LAST PART_NUMBER TMP_QCH14706KB18
J 0
(-2700 1275);
DISPLAY 0.489362 (-2700 1275);
PAINT SKYBLUE (-2700 1275);
DISPLAY INVISIBLE (-2700 1275);
FORCEPROP 1 LAST PATH I75
J 0
(-2700 1650);
DISPLAY 0.978723 (-2700 1650);
PAINT WHITE (-2700 1650);
DISPLAY INVISIBLE (-2700 1650);
FORCEPROP 2 LAST CDS_LIB pure_quanta
J 0
(-2750 1500);
DISPLAY INVISIBLE (-2750 1500);
FORCEADD Q_RES..1
(-2675 3400);
FORCEPROP 1 LAST LOCATION PR532
J 0
(-2725 3450);
DISPLAY 0.489362 (-2725 3450);
PAINT SKYBLUE (-2725 3450);
FORCEPROP 0 LAST $SEC 1
J 0
(-2725 3475);
DISPLAY 0.680851 (-2725 3475);
PAINT MONO (-2725 3475);
DISPLAY INVISIBLE (-2725 3475);
FORCEPROP 0 LAST CDS_SEC 1
J 0
(-2725 3475);
DISPLAY 0.680851 (-2725 3475);
DISPLAY INVISIBLE (-2725 3475);
FORCEPROP 1 LASTPIN (-2775 3400) $PN 1
J 0
(-2763 3412);
DISPLAY 0.787234 (-2763 3412);
PAINT MONO (-2763 3412);
DISPLAY INVISIBLE (-2763 3412);
FORCEPROP 1 LASTPIN (-2575 3400) $PN 2
J 0
(-2613 3412);
DISPLAY 0.787234 (-2613 3412);
PAINT MONO (-2613 3412);
DISPLAY INVISIBLE (-2613 3412);
FORCEPROP 1 LAST PACK_TYPE 0402LF
J 0
(-2575 3350);
DISPLAY 0.489362 (-2575 3350);
PAINT SKYBLUE (-2575 3350);
FORCEPROP 1 LAST VALUE 0
J 2
(-2675 3350);
DISPLAY 0.489362 (-2675 3350);
PAINT SKYBLUE (-2675 3350);
FORCEPROP 1 LAST TOLERANCE 5%
J 0
(-2650 3350);
DISPLAY 0.489362 (-2650 3350);
PAINT SKYBLUE (-2650 3350);
FORCEPROP 1 LAST WATTAGE 1/16W
J 2
(-2750 3350);
DISPLAY 0.489362 (-2750 3350);
PAINT SKYBLUE (-2750 3350);
FORCEPROP 1 LAST MATERIAL CHIP
J 0
(-3000 3350);
DISPLAY 0.489362 (-3000 3350);
PAINT SKYBLUE (-3000 3350);
FORCEPROP 1 LAST PART_NUMBER CS00002JB13
J 0
(-3350 3350);
DISPLAY 0.489362 (-3350 3350);
PAINT SKYBLUE (-3350 3350);
DISPLAY INVISIBLE (-3350 3350);
FORCEPROP 1 LAST PATH I76
J 0
(-2725 3550);
DISPLAY 0.978723 (-2725 3550);
PAINT WHITE (-2725 3550);
DISPLAY INVISIBLE (-2725 3550);
FORCEPROP 2 LAST CDS_LIB pure_quanta
J 0
(-2675 3400);
DISPLAY INVISIBLE (-2675 3400);
FORCEADD Q_RES..1
(-2675 3100);
FORCEPROP 1 LAST LOCATION PR32
J 0
(-2725 3150);
DISPLAY 0.489362 (-2725 3150);
PAINT SKYBLUE (-2725 3150);
FORCEPROP 0 LAST $SEC 1
J 0
(-2725 3200);
DISPLAY 0.680851 (-2725 3200);
PAINT MONO (-2725 3200);
DISPLAY INVISIBLE (-2725 3200);
FORCEPROP 0 LAST CDS_SEC 1
J 0
(-2725 3200);
DISPLAY 1.021277 (-2725 3200);
DISPLAY INVISIBLE (-2725 3200);
FORCEPROP 1 LASTPIN (-2775 3100) $PN 1
J 0
(-2763 3112);
DISPLAY 0.489362 (-2763 3112);
PAINT MONO (-2763 3112);
FORCEPROP 1 LASTPIN (-2575 3100) $PN 2
J 0
(-2613 3112);
DISPLAY 0.489362 (-2613 3112);
PAINT MONO (-2613 3112);
FORCEPROP 1 LAST PACK_TYPE 0402LF
J 0
(-2575 3050);
DISPLAY 0.489362 (-2575 3050);
PAINT SKYBLUE (-2575 3050);
FORCEPROP 1 LAST WATTAGE 1/16W
J 2
(-2750 3050);
DISPLAY 0.489362 (-2750 3050);
PAINT SKYBLUE (-2750 3050);
FORCEPROP 1 LAST VALUE 0
J 2
(-2675 3050);
DISPLAY 0.489362 (-2675 3050);
PAINT SKYBLUE (-2675 3050);
FORCEPROP 1 LAST TOLERANCE 5%
J 0
(-2650 3050);
DISPLAY 0.489362 (-2650 3050);
PAINT SKYBLUE (-2650 3050);
FORCEPROP 1 LAST MATERIAL CHIP
J 0
(-3000 3050);
DISPLAY 0.489362 (-3000 3050);
PAINT SKYBLUE (-3000 3050);
FORCEPROP 1 LAST PART_NUMBER CS00002JB13
J 0
(-3350 3050);
DISPLAY 0.489362 (-3350 3050);
PAINT SKYBLUE (-3350 3050);
DISPLAY INVISIBLE (-3350 3050);
FORCEPROP 1 LAST PATH I77
J 0
(-2725 3250);
DISPLAY 0.978723 (-2725 3250);
PAINT WHITE (-2725 3250);
DISPLAY INVISIBLE (-2725 3250);
FORCEPROP 2 LAST CDS_LIB pure_quanta
J 0
(-2675 3100);
DISPLAY INVISIBLE (-2675 3100);
FORCEADD Q_RES..1
(-6125 4300);
FORCEPROP 1 LAST LOCATION PR68
J 0
(-6325 4300);
DISPLAY 0.489362 (-6325 4300);
PAINT SKYBLUE (-6325 4300);
FORCEPROP 0 LAST $SEC 1
J 0
(-6175 4400);
DISPLAY 0.680851 (-6175 4400);
PAINT MONO (-6175 4400);
DISPLAY INVISIBLE (-6175 4400);
FORCEPROP 0 LAST CDS_SEC 1
J 0
(-6175 4400);
DISPLAY 1.021277 (-6175 4400);
DISPLAY INVISIBLE (-6175 4400);
FORCEPROP 1 LASTPIN (-6225 4300) $PN 1
J 0
(-6213 4312);
DISPLAY 0.489362 (-6213 4312);
PAINT MONO (-6213 4312);
FORCEPROP 1 LASTPIN (-6025 4300) $PN 2
J 0
(-6063 4312);
DISPLAY 0.489362 (-6063 4312);
PAINT MONO (-6063 4312);
FORCEPROP 1 LAST WATTAGE 1/16W
J 2
(-5750 4400);
DISPLAY 0.489362 (-5750 4400);
PAINT SKYBLUE (-5750 4400);
FORCEPROP 1 LAST MATERIAL CHIP
J 0
(-6000 4400);
DISPLAY 0.489362 (-6000 4400);
PAINT SKYBLUE (-6000 4400);
FORCEPROP 1 LAST TOLERANCE 5%
J 0
(-5950 4300);
DISPLAY 0.489362 (-5950 4300);
PAINT SKYBLUE (-5950 4300);
FORCEPROP 1 LAST VALUE 0
J 2
(-5975 4300);
DISPLAY 0.489362 (-5975 4300);
PAINT SKYBLUE (-5975 4300);
FORCEPROP 1 LAST PACK_TYPE 0402LF
J 0
(-5875 4300);
DISPLAY 0.489362 (-5875 4300);
PAINT SKYBLUE (-5875 4300);
FORCEPROP 1 LAST PART_NUMBER CS00002JB13
J 0
(-6000 4350);
DISPLAY 0.489362 (-6000 4350);
PAINT SKYBLUE (-6000 4350);
DISPLAY INVISIBLE (-6000 4350);
FORCEPROP 1 LAST PATH I78
J 0
(-6175 4450);
DISPLAY 0.978723 (-6175 4450);
PAINT WHITE (-6175 4450);
DISPLAY INVISIBLE (-6175 4450);
FORCEPROP 2 LAST CDS_LIB pure_quanta
J 0
(-6125 4300);
DISPLAY INVISIBLE (-6125 4300);
FORCEADD VCC_CORE..1
(-6425 4600);
FORCEPROP 3 LASTPIN (-6425 4550) SIG_NAME PVDDCR_CPU1_P0\g
J 0
(-6415 4560);
DISPLAY 0.659574 (-6415 4560);
PAINT MONO (-6415 4560);
DISPLAY INVISIBLE (-6415 4560);
FORCEPROP 1 LAST HDL_POWER PVDDCR_CPU1_P0
J 1
(-6425 4650);
DISPLAY 0.489362 (-6425 4650);
PAINT GREEN (-6425 4650);
FORCEPROP 1 LAST PATH I79
J 0
(-6375 4625);
DISPLAY 0.872340 (-6375 4625);
PAINT AQUA (-6375 4625);
DISPLAY INVISIBLE (-6375 4625);
FORCEPROP 2 LAST CDS_LIB pure_quanta_power
J 0
(-6425 4600);
DISPLAY INVISIBLE (-6425 4600);
FORCEADD Q_RES..2
(-6650 775);
FORCEPROP 1 LAST LOCATION PR54
J 0
(-6605 900);
DISPLAY 0.489362 (-6605 900);
PAINT SKYBLUE (-6605 900);
FORCEPROP 0 LAST $SEC 1
J 0
(-6600 950);
DISPLAY 0.680851 (-6600 950);
PAINT MONO (-6600 950);
DISPLAY INVISIBLE (-6600 950);
FORCEPROP 0 LAST CDS_SEC 1
J 0
(-6600 950);
DISPLAY 1.021277 (-6600 950);
DISPLAY INVISIBLE (-6600 950);
FORCEPROP 1 LASTPIN (-6650 875) $PN 1
J 0
(-6645 837);
DISPLAY 0.489362 (-6645 837);
PAINT MONO (-6645 837);
FORCEPROP 1 LASTPIN (-6650 675) $PN 2
J 0
(-6645 685);
DISPLAY 0.489362 (-6645 685);
PAINT MONO (-6645 685);
FORCEPROP 1 LAST PACK_TYPE 0402LF
J 0
(-6610 600);
DISPLAY 0.489362 (-6610 600);
PAINT SKYBLUE (-6610 600);
FORCEPROP 1 LAST VALUE 10K
J 0
(-6605 850);
DISPLAY 0.489362 (-6605 850);
PAINT SKYBLUE (-6605 850);
FORCEPROP 1 LAST MATERIAL CHIP
J 0
(-6610 700);
DISPLAY 0.489362 (-6610 700);
PAINT SKYBLUE (-6610 700);
FORCEPROP 1 LAST WATTAGE 1/16W
J 0
(-6610 750);
DISPLAY 0.489362 (-6610 750);
PAINT SKYBLUE (-6610 750);
FORCEPROP 1 LAST TOLERANCE 1%
J 0
(-6605 800);
DISPLAY 0.489362 (-6605 800);
PAINT SKYBLUE (-6605 800);
FORCEPROP 1 LAST PART_NUMBER CS31002FB08
J 0
(-6610 650);
DISPLAY 0.489362 (-6610 650);
PAINT SKYBLUE (-6610 650);
DISPLAY INVISIBLE (-6610 650);
FORCEPROP 1 LAST PATH I8
J 0
(-6600 950);
DISPLAY 0.978723 (-6600 950);
PAINT WHITE (-6600 950);
DISPLAY INVISIBLE (-6600 950);
FORCEPROP 2 LAST CDS_LIB pure_quanta
J 0
(-6650 775);
DISPLAY INVISIBLE (-6650 775);
FORCEADD Q_CAP..1
(-5675 4125);
FORCEPROP 1 LAST LOCATION PC68
J 0
(-5625 4250);
DISPLAY 0.489362 (-5625 4250);
PAINT SKYBLUE (-5625 4250);
FORCEPROP 0 LAST $SEC 1
J 0
(-5625 4250);
DISPLAY 0.680851 (-5625 4250);
PAINT MONO (-5625 4250);
DISPLAY INVISIBLE (-5625 4250);
FORCEPROP 0 LAST CDS_SEC 1
J 0
(-5625 4250);
DISPLAY 1.021277 (-5625 4250);
DISPLAY INVISIBLE (-5625 4250);
FORCEPROP 1 LASTPIN (-5675 4225) $PN 1
J 0
(-5665 4205);
DISPLAY 0.489362 (-5665 4205);
PAINT MONO (-5665 4205);
FORCEPROP 1 LASTPIN (-5675 4025) $PN 2
J 0
(-5665 4005);
DISPLAY 0.489362 (-5665 4005);
PAINT MONO (-5665 4005);
FORCEPROP 1 LAST VALUE 3300PF
J 0
(-5625 4200);
DISPLAY 0.489362 (-5625 4200);
PAINT SKYBLUE (-5625 4200);
FORCEPROP 1 LAST VOLTAGE 50V
J 0
(-5625 4150);
DISPLAY 0.489362 (-5625 4150);
PAINT SKYBLUE (-5625 4150);
FORCEPROP 1 LAST PACK_TYPE 0402
J 0
(-5625 4000);
DISPLAY 0.489362 (-5625 4000);
PAINT SKYBLUE (-5625 4000);
FORCEPROP 1 LAST MATERIAL X7R
J 0
(-5625 4050);
DISPLAY 0.489362 (-5625 4050);
PAINT SKYBLUE (-5625 4050);
FORCEPROP 1 LAST TOLERANCE 10%
J 0
(-5625 4100);
DISPLAY 0.489362 (-5625 4100);
PAINT SKYBLUE (-5625 4100);
FORCEPROP 1 LAST PART_NUMBER TMP_QCH2336K1B12
J 0
(-5625 3950);
DISPLAY 0.489362 (-5625 3950);
PAINT SKYBLUE (-5625 3950);
DISPLAY INVISIBLE (-5625 3950);
FORCEPROP 1 LAST PATH I80
J 0
(-5625 4275);
DISPLAY 0.978723 (-5625 4275);
PAINT WHITE (-5625 4275);
DISPLAY INVISIBLE (-5625 4275);
FORCEPROP 2 LAST CDS_LIB pure_quanta
J 0
(-5675 4125);
DISPLAY INVISIBLE (-5675 4125);
FORCEADD Q_RES..1
(-5750 4850);
FORCEPROP 1 LAST LOCATION R8073
J 0
(-5950 4850);
DISPLAY 0.489362 (-5950 4850);
PAINT SKYBLUE (-5950 4850);
FORCEPROP 0 LAST $SEC 1
J 0
(-5950 4875);
DISPLAY 0.680851 (-5950 4875);
PAINT MONO (-5950 4875);
DISPLAY INVISIBLE (-5950 4875);
FORCEPROP 0 LAST CDS_SEC 1
J 0
(-5950 4875);
DISPLAY 1.021277 (-5950 4875);
DISPLAY INVISIBLE (-5950 4875);
FORCEPROP 1 LASTPIN (-5850 4850) $PN 1
J 0
(-5838 4862);
DISPLAY 0.489362 (-5838 4862);
PAINT MONO (-5838 4862);
FORCEPROP 1 LASTPIN (-5650 4850) $PN 2
J 0
(-5688 4862);
DISPLAY 0.489362 (-5688 4862);
PAINT MONO (-5688 4862);
FORCEPROP 1 LAST MATERIAL CHIP
J 0
(-6075 4800);
DISPLAY 0.489362 (-6075 4800);
PAINT SKYBLUE (-6075 4800);
FORCEPROP 1 LAST PACK_TYPE 0402LF
J 0
(-5650 4800);
DISPLAY 0.489362 (-5650 4800);
PAINT SKYBLUE (-5650 4800);
FORCEPROP 1 LAST WATTAGE 1/16W
J 2
(-5825 4800);
DISPLAY 0.489362 (-5825 4800);
PAINT SKYBLUE (-5825 4800);
FORCEPROP 1 LAST TOLERANCE 5%
J 0
(-5725 4800);
DISPLAY 0.489362 (-5725 4800);
PAINT SKYBLUE (-5725 4800);
FORCEPROP 1 LAST VALUE 33
J 2
(-5750 4800);
DISPLAY 0.489362 (-5750 4800);
PAINT SKYBLUE (-5750 4800);
FORCEPROP 1 LAST PART_NUMBER CS03302JB10
J 0
(-6425 4800);
DISPLAY 0.489362 (-6425 4800);
PAINT SKYBLUE (-6425 4800);
DISPLAY INVISIBLE (-6425 4800);
FORCEPROP 2 LAST CDS_LIB pure_quanta
J 0
(-5750 4850);
DISPLAY INVISIBLE (-5750 4850);
FORCEPROP 1 LAST PATH I81
J 0
(-5800 5000);
DISPLAY 0.978723 (-5800 5000);
PAINT WHITE (-5800 5000);
DISPLAY INVISIBLE (-5800 5000);
FORCEADD Q_RES..1
(-5750 5000);
FORCEPROP 1 LAST LOCATION R8072
J 0
(-5950 5000);
DISPLAY 0.489362 (-5950 5000);
PAINT SKYBLUE (-5950 5000);
FORCEPROP 0 LAST $SEC 1
J 0
(-5950 5025);
DISPLAY 0.680851 (-5950 5025);
PAINT MONO (-5950 5025);
DISPLAY INVISIBLE (-5950 5025);
FORCEPROP 0 LAST CDS_SEC 1
J 0
(-5950 5025);
DISPLAY 1.021277 (-5950 5025);
DISPLAY INVISIBLE (-5950 5025);
FORCEPROP 1 LASTPIN (-5850 5000) $PN 1
J 0
(-5838 5012);
DISPLAY 0.489362 (-5838 5012);
PAINT MONO (-5838 5012);
FORCEPROP 1 LASTPIN (-5650 5000) $PN 2
J 0
(-5688 5012);
DISPLAY 0.489362 (-5688 5012);
PAINT MONO (-5688 5012);
FORCEPROP 1 LAST WATTAGE 1/16W
J 2
(-5825 4950);
DISPLAY 0.489362 (-5825 4950);
PAINT SKYBLUE (-5825 4950);
FORCEPROP 1 LAST MATERIAL CHIP
J 0
(-6075 4950);
DISPLAY 0.489362 (-6075 4950);
PAINT SKYBLUE (-6075 4950);
FORCEPROP 1 LAST PACK_TYPE 0402LF
J 0
(-5650 4950);
DISPLAY 0.489362 (-5650 4950);
PAINT SKYBLUE (-5650 4950);
FORCEPROP 1 LAST VALUE 0
J 2
(-5750 4950);
DISPLAY 0.489362 (-5750 4950);
PAINT SKYBLUE (-5750 4950);
FORCEPROP 1 LAST TOLERANCE 5%
J 0
(-5725 4950);
DISPLAY 0.489362 (-5725 4950);
PAINT SKYBLUE (-5725 4950);
FORCEPROP 1 LAST PART_NUMBER CS00002JB13
J 0
(-6425 4950);
DISPLAY 0.489362 (-6425 4950);
PAINT SKYBLUE (-6425 4950);
DISPLAY INVISIBLE (-6425 4950);
FORCEPROP 1 LAST PATH I82
J 0
(-5800 5150);
DISPLAY 0.978723 (-5800 5150);
PAINT WHITE (-5800 5150);
DISPLAY INVISIBLE (-5800 5150);
FORCEPROP 2 LAST CDS_LIB pure_quanta
J 0
(-5750 5000);
DISPLAY INVISIBLE (-5750 5000);
FORCEADD Q_RES..1
(-6475 5550);
FORCEPROP 1 LAST LOCATION R61
J 0
(-6525 5600);
DISPLAY 0.489362 (-6525 5600);
PAINT SKYBLUE (-6525 5600);
FORCEPROP 0 LAST $SEC 1
J 0
(-6075 5675);
DISPLAY 0.680851 (-6075 5675);
PAINT MONO (-6075 5675);
DISPLAY INVISIBLE (-6075 5675);
FORCEPROP 0 LAST CDS_SEC 1
J 0
(-6075 5675);
DISPLAY 1.021277 (-6075 5675);
DISPLAY INVISIBLE (-6075 5675);
FORCEPROP 1 LASTPIN (-6575 5550) $PN 1
J 0
(-6563 5562);
DISPLAY 0.489362 (-6563 5562);
PAINT MONO (-6563 5562);
FORCEPROP 1 LASTPIN (-6375 5550) $PN 2
J 0
(-6413 5562);
DISPLAY 0.489362 (-6413 5562);
PAINT MONO (-6413 5562);
FORCEPROP 1 LAST TOLERANCE 1%
J 0
(-5925 5600);
DISPLAY 0.489362 (-5925 5600);
PAINT SKYBLUE (-5925 5600);
FORCEPROP 1 LAST VALUE 49.9
J 2
(-5950 5600);
DISPLAY 0.489362 (-5950 5600);
PAINT SKYBLUE (-5950 5600);
FORCEPROP 1 LAST WATTAGE 1/16W
J 2
(-6075 5650);
DISPLAY 0.489362 (-6075 5650);
PAINT SKYBLUE (-6075 5650);
FORCEPROP 1 LAST MATERIAL CHIP
J 0
(-6350 5650);
DISPLAY 0.489362 (-6350 5650);
PAINT SKYBLUE (-6350 5650);
FORCEPROP 1 LAST PACK_TYPE 0402LF
J 0
(-5850 5600);
DISPLAY 0.489362 (-5850 5600);
PAINT SKYBLUE (-5850 5600);
FORCEPROP 1 LAST PART_NUMBER CS04992FB07
J 0
(-6350 5600);
DISPLAY 0.489362 (-6350 5600);
PAINT SKYBLUE (-6350 5600);
DISPLAY INVISIBLE (-6350 5600);
FORCEPROP 1 LAST PATH I83
J 0
(-6525 5700);
DISPLAY 0.978723 (-6525 5700);
PAINT WHITE (-6525 5700);
DISPLAY INVISIBLE (-6525 5700);
FORCEPROP 2 LAST CDS_LIB pure_quanta
J 0
(-6475 5550);
DISPLAY INVISIBLE (-6475 5550);
FORCEADD Q_RES..1
(-6475 5400);
FORCEPROP 1 LAST LOCATION PR62
J 0
(-6525 5450);
DISPLAY 0.489362 (-6525 5450);
PAINT SKYBLUE (-6525 5450);
FORCEPROP 0 LAST $SEC 1
J 0
(-6075 5525);
DISPLAY 0.680851 (-6075 5525);
PAINT MONO (-6075 5525);
DISPLAY INVISIBLE (-6075 5525);
FORCEPROP 0 LAST CDS_SEC 1
J 0
(-6075 5525);
DISPLAY 1.021277 (-6075 5525);
DISPLAY INVISIBLE (-6075 5525);
FORCEPROP 1 LASTPIN (-6575 5400) $PN 1
J 0
(-6563 5412);
DISPLAY 0.489362 (-6563 5412);
PAINT MONO (-6563 5412);
FORCEPROP 1 LASTPIN (-6375 5400) $PN 2
J 0
(-6413 5412);
DISPLAY 0.489362 (-6413 5412);
PAINT MONO (-6413 5412);
FORCEPROP 1 LAST PACK_TYPE 0402LF
J 0
(-5875 5450);
DISPLAY 0.489362 (-5875 5450);
PAINT SKYBLUE (-5875 5450);
FORCEPROP 1 LAST TOLERANCE 5%
J 0
(-5950 5450);
DISPLAY 0.489362 (-5950 5450);
PAINT SKYBLUE (-5950 5450);
FORCEPROP 1 LAST VALUE 0
J 2
(-5975 5450);
DISPLAY 0.489362 (-5975 5450);
PAINT SKYBLUE (-5975 5450);
FORCEPROP 1 LAST WATTAGE 1/16W
J 2
(-6075 5500);
DISPLAY 0.489362 (-6075 5500);
PAINT SKYBLUE (-6075 5500);
FORCEPROP 1 LAST MATERIAL CHIP
J 0
(-6350 5500);
DISPLAY 0.489362 (-6350 5500);
PAINT SKYBLUE (-6350 5500);
FORCEPROP 1 LAST PART_NUMBER CS00002JB13
J 0
(-6350 5450);
DISPLAY 0.489362 (-6350 5450);
PAINT SKYBLUE (-6350 5450);
DISPLAY INVISIBLE (-6350 5450);
FORCEPROP 1 LAST PATH I84
J 0
(-6525 5550);
DISPLAY 0.978723 (-6525 5550);
PAINT WHITE (-6525 5550);
DISPLAY INVISIBLE (-6525 5550);
FORCEPROP 2 LAST CDS_LIB pure_quanta
J 0
(-6475 5400);
DISPLAY INVISIBLE (-6475 5400);
FORCEADD Q_RES..1
(-5750 5150);
FORCEPROP 1 LAST LOCATION R8071
J 0
(-5950 5150);
DISPLAY 0.489362 (-5950 5150);
PAINT SKYBLUE (-5950 5150);
FORCEPROP 0 LAST $SEC 1
J 0
(-5800 5250);
DISPLAY 0.680851 (-5800 5250);
PAINT MONO (-5800 5250);
DISPLAY INVISIBLE (-5800 5250);
FORCEPROP 0 LAST CDS_SEC 1
J 0
(-5800 5250);
DISPLAY 1.021277 (-5800 5250);
DISPLAY INVISIBLE (-5800 5250);
FORCEPROP 1 LASTPIN (-5850 5150) $PN 1
J 0
(-5838 5162);
DISPLAY 0.489362 (-5838 5162);
PAINT MONO (-5838 5162);
FORCEPROP 1 LASTPIN (-5650 5150) $PN 2
J 0
(-5688 5162);
DISPLAY 0.489362 (-5688 5162);
PAINT MONO (-5688 5162);
FORCEPROP 1 LAST PACK_TYPE 0402LF
J 0
(-5650 5100);
DISPLAY 0.489362 (-5650 5100);
PAINT SKYBLUE (-5650 5100);
FORCEPROP 1 LAST MATERIAL CHIP
J 0
(-6075 5100);
DISPLAY 0.489362 (-6075 5100);
PAINT SKYBLUE (-6075 5100);
FORCEPROP 1 LAST WATTAGE 1/16W
J 2
(-5825 5100);
DISPLAY 0.489362 (-5825 5100);
PAINT SKYBLUE (-5825 5100);
FORCEPROP 1 LAST VALUE 0
J 2
(-5750 5100);
DISPLAY 0.489362 (-5750 5100);
PAINT SKYBLUE (-5750 5100);
FORCEPROP 1 LAST TOLERANCE 5%
J 0
(-5725 5100);
DISPLAY 0.489362 (-5725 5100);
PAINT SKYBLUE (-5725 5100);
FORCEPROP 1 LAST PART_NUMBER CS00002JB13
J 0
(-6425 5100);
DISPLAY 0.489362 (-6425 5100);
PAINT SKYBLUE (-6425 5100);
DISPLAY INVISIBLE (-6425 5100);
FORCEPROP 1 LAST PATH I85
J 0
(-5800 5300);
DISPLAY 0.978723 (-5800 5300);
PAINT WHITE (-5800 5300);
DISPLAY INVISIBLE (-5800 5300);
FORCEPROP 2 LAST CDS_LIB pure_quanta
J 0
(-5750 5150);
DISPLAY INVISIBLE (-5750 5150);
FORCEADD Q_CAP..2
(-5650 6025);
FORCEPROP 1 LAST LOCATION C8069
J 1
(-5825 6025);
DISPLAY 0.489362 (-5825 6025);
PAINT SKYBLUE (-5825 6025);
FORCEPROP 0 LAST $SEC 1
J 0
(-5700 6125);
DISPLAY 0.680851 (-5700 6125);
PAINT MONO (-5700 6125);
DISPLAY INVISIBLE (-5700 6125);
FORCEPROP 0 LAST CDS_SEC 1
J 0
(-5700 6125);
DISPLAY 1.021277 (-5700 6125);
DISPLAY INVISIBLE (-5700 6125);
FORCEPROP 1 LASTPIN (-5750 6025) $PN 1
J 0
(-5760 6040);
DISPLAY 0.489362 (-5760 6040);
PAINT MONO (-5760 6040);
FORCEPROP 1 LASTPIN (-5550 6025) $PN 2
J 0
(-5565 6040);
DISPLAY 0.489362 (-5565 6040);
PAINT MONO (-5565 6040);
FORCEPROP 1 LAST MATERIAL X7R
J 0
(-5175 6025);
DISPLAY 0.489362 (-5175 6025);
PAINT SKYBLUE (-5175 6025);
FORCEPROP 1 LAST PACK_TYPE 0402
J 1
(-5150 5975);
DISPLAY 0.489362 (-5150 5975);
PAINT SKYBLUE (-5150 5975);
FORCEPROP 1 LAST TOLERANCE 5%
J 2
(-5000 5975);
DISPLAY 0.489362 (-5000 5975);
PAINT SKYBLUE (-5000 5975);
FORCEPROP 1 LAST VALUE 1000PF
J 2
(-5325 6025);
DISPLAY 0.489362 (-5325 6025);
PAINT SKYBLUE (-5325 6025);
FORCEPROP 1 LAST VOLTAGE 50V
J 0
(-5300 6025);
DISPLAY 0.489362 (-5300 6025);
PAINT SKYBLUE (-5300 6025);
FORCEPROP 1 LAST PART_NUMBER TMP_QCH21006JB10
J 1
(-5375 5975);
DISPLAY 0.489362 (-5375 5975);
PAINT SKYBLUE (-5375 5975);
DISPLAY INVISIBLE (-5375 5975);
FORCEPROP 1 LAST PATH I86
J 0
(-5650 6225);
DISPLAY 0.978723 (-5650 6225);
PAINT WHITE (-5650 6225);
DISPLAY INVISIBLE (-5650 6225);
FORCEPROP 2 LAST CDS_LIB pure_quanta
J 0
(-5650 6025);
DISPLAY INVISIBLE (-5650 6025);
FORCEADD UNIVERSAL_GND..1
R 1
(-4925 6025);
FORCEPROP 3 LASTPIN (-4975 6025) SIG_NAME GND\g
J 0
(-4965 6035);
DISPLAY 0.659574 (-4965 6035);
PAINT MONO (-4965 6035);
DISPLAY INVISIBLE (-4965 6035);
FORCEPROP 1 LAST PATH I87
R 1
J 0
(-4925 6100);
DISPLAY 0.872340 (-4925 6100);
PAINT AQUA (-4925 6100);
DISPLAY INVISIBLE (-4925 6100);
FORCEPROP 1 LAST HDL_POWER GND
R 1
J 1
(-4850 6050);
DISPLAY 0.872340 (-4850 6050);
PAINT GREEN (-4850 6050);
DISPLAY INVISIBLE (-4850 6050);
FORCEPROP 2 LAST CDS_LIB pure_quanta_power
J 0
(-4925 6025);
PAINT MONO (-4925 6025);
DISPLAY INVISIBLE (-4925 6025);
FORCEADD Q_RES..1
(-6475 6150);
FORCEPROP 1 LAST LOCATION R8058
J 0
(-6675 6150);
DISPLAY 0.489362 (-6675 6150);
PAINT SKYBLUE (-6675 6150);
FORCEPROP 0 LAST $SEC 1
J 0
(-6525 6250);
DISPLAY 0.680851 (-6525 6250);
PAINT MONO (-6525 6250);
DISPLAY INVISIBLE (-6525 6250);
FORCEPROP 0 LAST CDS_SEC 1
J 0
(-6525 6250);
DISPLAY 1.021277 (-6525 6250);
DISPLAY INVISIBLE (-6525 6250);
FORCEPROP 1 LASTPIN (-6575 6150) $PN 1
J 0
(-6563 6162);
DISPLAY 0.489362 (-6563 6162);
PAINT MONO (-6563 6162);
FORCEPROP 1 LASTPIN (-6375 6150) $PN 2
J 0
(-6413 6162);
DISPLAY 0.489362 (-6413 6162);
PAINT MONO (-6413 6162);
FORCEPROP 1 LAST PACK_TYPE 0402LF
J 0
(-6225 6150);
DISPLAY 0.489362 (-6225 6150);
PAINT SKYBLUE (-6225 6150);
FORCEPROP 1 LAST VALUE 0
J 2
(-6325 6150);
DISPLAY 0.489362 (-6325 6150);
PAINT SKYBLUE (-6325 6150);
FORCEPROP 1 LAST TOLERANCE 5%
J 0
(-6300 6150);
DISPLAY 0.489362 (-6300 6150);
PAINT SKYBLUE (-6300 6150);
FORCEPROP 1 LAST WATTAGE 1/16W
J 2
(-6100 6250);
DISPLAY 0.489362 (-6100 6250);
PAINT SKYBLUE (-6100 6250);
FORCEPROP 1 LAST MATERIAL CHIP
J 0
(-6350 6250);
DISPLAY 0.489362 (-6350 6250);
PAINT SKYBLUE (-6350 6250);
FORCEPROP 1 LAST PART_NUMBER CS00002JB13
J 0
(-6350 6200);
DISPLAY 0.489362 (-6350 6200);
PAINT SKYBLUE (-6350 6200);
DISPLAY INVISIBLE (-6350 6200);
FORCEPROP 1 LAST PATH I88
J 0
(-6525 6300);
DISPLAY 0.978723 (-6525 6300);
PAINT WHITE (-6525 6300);
DISPLAY INVISIBLE (-6525 6300);
FORCEPROP 2 LAST CDS_LIB pure_quanta
J 0
(-6475 6150);
DISPLAY INVISIBLE (-6475 6150);
FORCEADD Q_RES..1
(-6475 6300);
FORCEPROP 1 LAST LOCATION R8057
J 0
(-6675 6300);
DISPLAY 0.489362 (-6675 6300);
PAINT SKYBLUE (-6675 6300);
FORCEPROP 0 LAST $SEC 1
J 0
(-6525 6400);
DISPLAY 0.680851 (-6525 6400);
PAINT MONO (-6525 6400);
DISPLAY INVISIBLE (-6525 6400);
FORCEPROP 0 LAST CDS_SEC 1
J 0
(-6525 6400);
DISPLAY 1.021277 (-6525 6400);
DISPLAY INVISIBLE (-6525 6400);
FORCEPROP 1 LASTPIN (-6575 6300) $PN 1
J 0
(-6563 6312);
DISPLAY 0.489362 (-6563 6312);
PAINT MONO (-6563 6312);
FORCEPROP 1 LASTPIN (-6375 6300) $PN 2
J 0
(-6413 6312);
DISPLAY 0.489362 (-6413 6312);
PAINT MONO (-6413 6312);
FORCEPROP 1 LAST TOLERANCE 5%
J 0
(-6300 6300);
DISPLAY 0.489362 (-6300 6300);
PAINT SKYBLUE (-6300 6300);
FORCEPROP 1 LAST WATTAGE 1/16W
J 2
(-6100 6400);
DISPLAY 0.489362 (-6100 6400);
PAINT SKYBLUE (-6100 6400);
FORCEPROP 1 LAST PACK_TYPE 0402LF
J 0
(-6225 6300);
DISPLAY 0.489362 (-6225 6300);
PAINT SKYBLUE (-6225 6300);
FORCEPROP 1 LAST MATERIAL CHIP
J 0
(-6350 6400);
DISPLAY 0.489362 (-6350 6400);
PAINT SKYBLUE (-6350 6400);
FORCEPROP 1 LAST VALUE 33
J 2
(-6325 6300);
DISPLAY 0.489362 (-6325 6300);
PAINT SKYBLUE (-6325 6300);
FORCEPROP 1 LAST PART_NUMBER CS03302JB10
J 0
(-6350 6350);
DISPLAY 0.489362 (-6350 6350);
PAINT SKYBLUE (-6350 6350);
DISPLAY INVISIBLE (-6350 6350);
FORCEPROP 1 LAST PATH I89
J 0
(-6525 6450);
DISPLAY 0.978723 (-6525 6450);
PAINT WHITE (-6525 6450);
DISPLAY INVISIBLE (-6525 6450);
FORCEPROP 2 LAST CDS_LIB pure_quanta
J 0
(-6475 6300);
DISPLAY INVISIBLE (-6475 6300);
FORCEADD Q_RES..1
(-6975 950);
FORCEPROP 1 LAST LOCATION PR53
J 0
(-7100 1000);
DISPLAY 0.489362 (-7100 1000);
PAINT SKYBLUE (-7100 1000);
FORCEPROP 0 LAST $SEC 1
J 0
(-7025 1050);
DISPLAY 0.680851 (-7025 1050);
PAINT MONO (-7025 1050);
DISPLAY INVISIBLE (-7025 1050);
FORCEPROP 0 LAST CDS_SEC 1
J 0
(-7025 1050);
DISPLAY 1.021277 (-7025 1050);
DISPLAY INVISIBLE (-7025 1050);
FORCEPROP 1 LASTPIN (-7075 950) $PN 1
J 0
(-7063 962);
DISPLAY 0.489362 (-7063 962);
PAINT MONO (-7063 962);
FORCEPROP 1 LASTPIN (-6875 950) $PN 2
J 0
(-6913 962);
DISPLAY 0.489362 (-6913 962);
PAINT MONO (-6913 962);
FORCEPROP 1 LAST VALUE 40.2K
J 2
(-6825 1000);
DISPLAY 0.489362 (-6825 1000);
PAINT SKYBLUE (-6825 1000);
FORCEPROP 1 LAST MATERIAL CHIP
J 0
(-6975 900);
DISPLAY 0.489362 (-6975 900);
PAINT SKYBLUE (-6975 900);
FORCEPROP 1 LAST TOLERANCE 1%
J 0
(-6875 900);
DISPLAY 0.489362 (-6875 900);
PAINT SKYBLUE (-6875 900);
FORCEPROP 1 LAST PACK_TYPE 0402LF
J 0
(-7125 900);
DISPLAY 0.489362 (-7125 900);
PAINT SKYBLUE (-7125 900);
FORCEPROP 1 LAST PART_NUMBER CS34022FB04
J 0
(-7100 850);
DISPLAY 0.510638 (-7100 850);
PAINT SKYBLUE (-7100 850);
DISPLAY INVISIBLE (-7100 850);
FORCEPROP 1 LAST PATH I9
J 0
(-7025 1100);
DISPLAY 0.978723 (-7025 1100);
PAINT WHITE (-7025 1100);
DISPLAY INVISIBLE (-7025 1100);
FORCEPROP 2 LAST CDS_LIB pure_quanta
J 0
(-6975 950);
DISPLAY INVISIBLE (-6975 950);
FORCEPROP 1 LAST WATTAGE 1/16W
J 2
(-6600 850);
DISPLAY 0.510638 (-6600 850);
PAINT SKYBLUE (-6600 850);
DISPLAY INVISIBLE (-6600 850);
FORCEADD Q_RES..1
(-6475 6450);
FORCEPROP 1 LAST LOCATION R8056
J 0
(-6675 6450);
DISPLAY 0.489362 (-6675 6450);
PAINT SKYBLUE (-6675 6450);
FORCEPROP 0 LAST $SEC 1
J 0
(-6525 6550);
DISPLAY 0.680851 (-6525 6550);
PAINT MONO (-6525 6550);
DISPLAY INVISIBLE (-6525 6550);
FORCEPROP 0 LAST CDS_SEC 1
J 0
(-6525 6550);
DISPLAY 1.021277 (-6525 6550);
DISPLAY INVISIBLE (-6525 6550);
FORCEPROP 1 LASTPIN (-6575 6450) $PN 1
J 0
(-6563 6462);
DISPLAY 0.489362 (-6563 6462);
PAINT MONO (-6563 6462);
FORCEPROP 1 LASTPIN (-6375 6450) $PN 2
J 0
(-6413 6462);
DISPLAY 0.489362 (-6413 6462);
PAINT MONO (-6413 6462);
FORCEPROP 1 LAST PACK_TYPE 0402LF
J 0
(-6175 6450);
DISPLAY 0.489362 (-6175 6450);
PAINT SKYBLUE (-6175 6450);
FORCEPROP 1 LAST VALUE 1K
J 2
(-6300 6450);
DISPLAY 0.489362 (-6300 6450);
PAINT SKYBLUE (-6300 6450);
FORCEPROP 1 LAST MATERIAL CHIP
J 0
(-6350 6550);
DISPLAY 0.489362 (-6350 6550);
PAINT SKYBLUE (-6350 6550);
FORCEPROP 1 LAST WATTAGE 1/16W
J 2
(-6100 6550);
DISPLAY 0.489362 (-6100 6550);
PAINT SKYBLUE (-6100 6550);
FORCEPROP 1 LAST TOLERANCE 1%
J 0
(-6275 6450);
DISPLAY 0.489362 (-6275 6450);
PAINT SKYBLUE (-6275 6450);
FORCEPROP 1 LAST PART_NUMBER CS21002FB06
J 0
(-6350 6500);
DISPLAY 0.489362 (-6350 6500);
PAINT SKYBLUE (-6350 6500);
DISPLAY INVISIBLE (-6350 6500);
FORCEPROP 1 LAST PATH I90
J 0
(-6525 6600);
DISPLAY 0.978723 (-6525 6600);
PAINT WHITE (-6525 6600);
DISPLAY INVISIBLE (-6525 6600);
FORCEPROP 2 LAST CDS_LIB pure_quanta
J 0
(-6475 6450);
DISPLAY INVISIBLE (-6475 6450);
FORCEADD Q_CAP..2
(-5625 6450);
FORCEPROP 1 LAST LOCATION C8070
J 1
(-5825 6450);
DISPLAY 0.489362 (-5825 6450);
PAINT SKYBLUE (-5825 6450);
FORCEPROP 0 LAST $SEC 1
J 0
(-5675 6550);
DISPLAY 0.680851 (-5675 6550);
PAINT MONO (-5675 6550);
DISPLAY INVISIBLE (-5675 6550);
FORCEPROP 0 LAST CDS_SEC 1
J 0
(-5675 6550);
DISPLAY 1.021277 (-5675 6550);
DISPLAY INVISIBLE (-5675 6550);
FORCEPROP 1 LASTPIN (-5725 6450) $PN 1
J 0
(-5735 6465);
DISPLAY 0.489362 (-5735 6465);
PAINT MONO (-5735 6465);
FORCEPROP 1 LASTPIN (-5525 6450) $PN 2
J 0
(-5540 6465);
DISPLAY 0.489362 (-5540 6465);
PAINT MONO (-5540 6465);
FORCEPROP 1 LAST TOLERANCE 5%
J 2
(-4975 6400);
DISPLAY 0.489362 (-4975 6400);
PAINT SKYBLUE (-4975 6400);
FORCEPROP 1 LAST VOLTAGE 50V
J 0
(-5275 6450);
DISPLAY 0.489362 (-5275 6450);
PAINT SKYBLUE (-5275 6450);
FORCEPROP 1 LAST VALUE 1000PF
J 2
(-5300 6450);
DISPLAY 0.489362 (-5300 6450);
PAINT SKYBLUE (-5300 6450);
FORCEPROP 1 LAST PACK_TYPE 0402
J 1
(-5125 6400);
DISPLAY 0.489362 (-5125 6400);
PAINT SKYBLUE (-5125 6400);
FORCEPROP 1 LAST MATERIAL EMPTY
J 0
(-5175 6450);
DISPLAY 0.489362 (-5175 6450);
PAINT RED (-5175 6450);
FORCEPROP 1 LAST PART_NUMBER TMP_QCH21006JB10
J 1
(-5350 6400);
DISPLAY 0.489362 (-5350 6400);
PAINT SKYBLUE (-5350 6400);
DISPLAY INVISIBLE (-5350 6400);
FORCEPROP 2 LAST CDS_LIB pure_quanta
J 0
(-5625 6450);
DISPLAY INVISIBLE (-5625 6450);
FORCEPROP 1 LAST PATH I91
J 0
(-5625 6650);
DISPLAY 0.978723 (-5625 6650);
PAINT WHITE (-5625 6650);
DISPLAY INVISIBLE (-5625 6650);
FORCEADD UNIVERSAL_GND..1
R 1
(-4925 6450);
FORCEPROP 3 LASTPIN (-4975 6450) SIG_NAME GND\g
J 0
(-4965 6460);
DISPLAY 0.659574 (-4965 6460);
PAINT MONO (-4965 6460);
DISPLAY INVISIBLE (-4965 6460);
FORCEPROP 1 LAST PATH I92
R 1
J 0
(-4925 6525);
DISPLAY 0.872340 (-4925 6525);
PAINT AQUA (-4925 6525);
DISPLAY INVISIBLE (-4925 6525);
FORCEPROP 1 LAST HDL_POWER GND
R 1
J 1
(-4850 6475);
DISPLAY 0.872340 (-4850 6475);
PAINT GREEN (-4850 6475);
DISPLAY INVISIBLE (-4850 6475);
FORCEPROP 2 LAST CDS_LIB pure_quanta_power
J 0
(-4925 6450);
PAINT MONO (-4925 6450);
DISPLAY INVISIBLE (-4925 6450);
FORCEADD UNIVERSAL_GND..1
(-3075 5450);
FORCEPROP 3 LASTPIN (-3075 5500) SIG_NAME GND\g
J 0
(-3065 5510);
DISPLAY 0.659574 (-3065 5510);
PAINT MONO (-3065 5510);
DISPLAY INVISIBLE (-3065 5510);
FORCEPROP 1 LAST PATH I93
J 0
(-3000 5450);
DISPLAY 0.872340 (-3000 5450);
PAINT AQUA (-3000 5450);
DISPLAY INVISIBLE (-3000 5450);
FORCEPROP 1 LAST HDL_POWER GND
J 1
(-3050 5375);
DISPLAY 0.872340 (-3050 5375);
PAINT GREEN (-3050 5375);
DISPLAY INVISIBLE (-3050 5375);
FORCEPROP 2 LAST CDS_LIB pure_quanta_power
J 0
(-3075 5450);
DISPLAY INVISIBLE (-3075 5450);
FORCEADD Q_CAP..1
(-3075 5675);
FORCEPROP 1 LAST LOCATION PC15
J 0
(-3025 5775);
DISPLAY 0.489362 (-3025 5775);
PAINT SKYBLUE (-3025 5775);
FORCEPROP 0 LAST $SEC 1
J 0
(-3025 5800);
DISPLAY 0.680851 (-3025 5800);
PAINT MONO (-3025 5800);
DISPLAY INVISIBLE (-3025 5800);
FORCEPROP 0 LAST CDS_SEC 1
J 0
(-3025 5800);
DISPLAY 1.021277 (-3025 5800);
DISPLAY INVISIBLE (-3025 5800);
FORCEPROP 1 LASTPIN (-3075 5775) $PN 1
J 0
(-3065 5755);
DISPLAY 0.489362 (-3065 5755);
PAINT MONO (-3065 5755);
FORCEPROP 1 LASTPIN (-3075 5575) $PN 2
J 0
(-3065 5555);
DISPLAY 0.489362 (-3065 5555);
PAINT MONO (-3065 5555);
FORCEPROP 1 LAST VOLTAGE 25V
J 0
(-3025 5675);
DISPLAY 0.489362 (-3025 5675);
PAINT SKYBLUE (-3025 5675);
FORCEPROP 1 LAST TOLERANCE 10%
J 0
(-3025 5625);
DISPLAY 0.489362 (-3025 5625);
PAINT SKYBLUE (-3025 5625);
FORCEPROP 1 LAST MATERIAL X7R
J 0
(-3025 5575);
DISPLAY 0.489362 (-3025 5575);
PAINT SKYBLUE (-3025 5575);
FORCEPROP 1 LAST PACK_TYPE 0402
J 0
(-3025 5475);
DISPLAY 0.489362 (-3025 5475);
PAINT SKYBLUE (-3025 5475);
FORCEPROP 1 LAST VALUE 0.1UF
J 0
(-3025 5725);
DISPLAY 0.489362 (-3025 5725);
PAINT SKYBLUE (-3025 5725);
FORCEPROP 1 LAST PART_NUMBER CH4104K1B00
J 0
(-3025 5525);
DISPLAY 0.489362 (-3025 5525);
PAINT SKYBLUE (-3025 5525);
DISPLAY INVISIBLE (-3025 5525);
FORCEPROP 1 LAST PATH I94
J 0
(-3025 5825);
DISPLAY 0.978723 (-3025 5825);
PAINT WHITE (-3025 5825);
DISPLAY INVISIBLE (-3025 5825);
FORCEPROP 2 LAST CDS_LIB pure_quanta
J 0
(-3075 5675);
DISPLAY INVISIBLE (-3075 5675);
FORCEADD UNIVERSAL_GND..1
(-3075 5925);
FORCEPROP 3 LASTPIN (-3075 5975) SIG_NAME GND\g
J 0
(-3065 5985);
DISPLAY 0.659574 (-3065 5985);
PAINT MONO (-3065 5985);
DISPLAY INVISIBLE (-3065 5985);
FORCEPROP 1 LAST PATH I95
J 0
(-3000 5925);
DISPLAY 0.872340 (-3000 5925);
PAINT AQUA (-3000 5925);
DISPLAY INVISIBLE (-3000 5925);
FORCEPROP 1 LAST HDL_POWER GND
J 1
(-3050 5850);
DISPLAY 0.872340 (-3050 5850);
PAINT GREEN (-3050 5850);
DISPLAY INVISIBLE (-3050 5850);
FORCEPROP 2 LAST CDS_LIB pure_quanta_power
J 0
(-3075 5925);
DISPLAY INVISIBLE (-3075 5925);
FORCEADD Q_CAP..1
(-3075 6150);
FORCEPROP 1 LAST LOCATION PC14
J 0
(-3025 6250);
DISPLAY 0.489362 (-3025 6250);
PAINT SKYBLUE (-3025 6250);
FORCEPROP 0 LAST $SEC 1
J 0
(-3025 6275);
DISPLAY 0.680851 (-3025 6275);
PAINT MONO (-3025 6275);
DISPLAY INVISIBLE (-3025 6275);
FORCEPROP 0 LAST CDS_SEC 1
J 0
(-3025 6275);
DISPLAY 1.021277 (-3025 6275);
DISPLAY INVISIBLE (-3025 6275);
FORCEPROP 1 LASTPIN (-3075 6250) $PN 1
J 0
(-3065 6230);
DISPLAY 0.489362 (-3065 6230);
PAINT MONO (-3065 6230);
FORCEPROP 1 LASTPIN (-3075 6050) $PN 2
J 0
(-3065 6030);
DISPLAY 0.489362 (-3065 6030);
PAINT MONO (-3065 6030);
FORCEPROP 1 LAST MATERIAL X7R
J 0
(-3025 6050);
DISPLAY 0.489362 (-3025 6050);
PAINT SKYBLUE (-3025 6050);
FORCEPROP 1 LAST TOLERANCE 10%
J 0
(-3025 6100);
DISPLAY 0.489362 (-3025 6100);
PAINT SKYBLUE (-3025 6100);
FORCEPROP 1 LAST VALUE 0.1UF
J 0
(-3025 6200);
DISPLAY 0.489362 (-3025 6200);
PAINT SKYBLUE (-3025 6200);
FORCEPROP 1 LAST VOLTAGE 25V
J 0
(-3025 6150);
DISPLAY 0.489362 (-3025 6150);
PAINT SKYBLUE (-3025 6150);
FORCEPROP 1 LAST PACK_TYPE 0402
J 0
(-3025 5950);
DISPLAY 0.489362 (-3025 5950);
PAINT SKYBLUE (-3025 5950);
FORCEPROP 1 LAST PART_NUMBER CH4104K1B00
J 0
(-3025 6000);
DISPLAY 0.489362 (-3025 6000);
PAINT SKYBLUE (-3025 6000);
DISPLAY INVISIBLE (-3025 6000);
FORCEPROP 1 LAST PATH I96
J 0
(-3025 6300);
DISPLAY 0.978723 (-3025 6300);
PAINT WHITE (-3025 6300);
DISPLAY INVISIBLE (-3025 6300);
FORCEPROP 2 LAST CDS_LIB pure_quanta
J 0
(-3075 6150);
DISPLAY INVISIBLE (-3075 6150);
FORCEADD UNIVERSAL_GND..1
(-2750 5450);
FORCEPROP 3 LASTPIN (-2750 5500) SIG_NAME GND\g
J 0
(-2740 5510);
DISPLAY 0.659574 (-2740 5510);
PAINT MONO (-2740 5510);
DISPLAY INVISIBLE (-2740 5510);
FORCEPROP 1 LAST PATH I97
J 0
(-2675 5450);
DISPLAY 0.872340 (-2675 5450);
PAINT AQUA (-2675 5450);
DISPLAY INVISIBLE (-2675 5450);
FORCEPROP 1 LAST HDL_POWER GND
J 1
(-2725 5375);
DISPLAY 0.872340 (-2725 5375);
PAINT GREEN (-2725 5375);
DISPLAY INVISIBLE (-2725 5375);
FORCEPROP 2 LAST CDS_LIB pure_quanta_power
J 0
(-2750 5450);
DISPLAY INVISIBLE (-2750 5450);
FORCEADD Q_CAP..1
(-2750 5650);
FORCEPROP 1 LAST LOCATION PC76
J 0
(-2700 5775);
DISPLAY 0.489362 (-2700 5775);
PAINT SKYBLUE (-2700 5775);
FORCEPROP 2 LAST $SEC 1
J 0
(-2700 5850);
DISPLAY 0.680851 (-2700 5850);
PAINT MONO (-2700 5850);
DISPLAY INVISIBLE (-2700 5850);
FORCEPROP 2 LAST CDS_SEC 1
J 0
(-2700 5850);
DISPLAY 1.021277 (-2700 5850);
DISPLAY INVISIBLE (-2700 5850);
FORCEPROP 1 LASTPIN (-2750 5750) $PN 1
J 0
(-2740 5730);
DISPLAY 0.489362 (-2740 5730);
FORCEPROP 1 LASTPIN (-2750 5550) $PN 2
J 0
(-2740 5530);
DISPLAY 0.489362 (-2740 5530);
FORCEPROP 1 LAST TOLERANCE 20%
J 0
(-2700 5625);
DISPLAY 0.489362 (-2700 5625);
PAINT SKYBLUE (-2700 5625);
FORCEPROP 1 LAST PACK_TYPE C0402
J 0
(-2700 5525);
DISPLAY 0.489362 (-2700 5525);
PAINT SKYBLUE (-2700 5525);
FORCEPROP 1 LAST VOLTAGE 6.3V
J 0
(-2700 5675);
DISPLAY 0.489362 (-2700 5675);
PAINT SKYBLUE (-2700 5675);
FORCEPROP 1 LAST VALUE 10UF
J 0
(-2700 5725);
DISPLAY 0.489362 (-2700 5725);
PAINT SKYBLUE (-2700 5725);
FORCEPROP 1 LAST MATERIAL X6S
J 0
(-2700 5575);
DISPLAY 0.489362 (-2700 5575);
PAINT SKYBLUE (-2700 5575);
FORCEPROP 1 LAST PART_NUMBER CH6101MEB03
J 0
(-2700 5475);
DISPLAY 0.489362 (-2700 5475);
PAINT SKYBLUE (-2700 5475);
DISPLAY INVISIBLE (-2700 5475);
FORCEPROP 1 LAST PATH I98
J 0
(-2700 5800);
DISPLAY 0.978723 (-2700 5800);
PAINT WHITE (-2700 5800);
DISPLAY INVISIBLE (-2700 5800);
FORCEPROP 2 LAST CDS_LIB pure_quanta
J 0
(-2750 5650);
PAINT MONO (-2750 5650);
DISPLAY INVISIBLE (-2750 5650);
FORCEADD UNIVERSAL_GND..1
(-2750 5925);
FORCEPROP 3 LASTPIN (-2750 5975) SIG_NAME GND\g
J 0
(-2740 5985);
DISPLAY 0.659574 (-2740 5985);
PAINT MONO (-2740 5985);
DISPLAY INVISIBLE (-2740 5985);
FORCEPROP 1 LAST PATH I99
J 0
(-2675 5925);
DISPLAY 0.872340 (-2675 5925);
PAINT AQUA (-2675 5925);
DISPLAY INVISIBLE (-2675 5925);
FORCEPROP 1 LAST HDL_POWER GND
J 1
(-2725 5850);
DISPLAY 0.872340 (-2725 5850);
PAINT GREEN (-2725 5850);
DISPLAY INVISIBLE (-2725 5850);
FORCEPROP 2 LAST CDS_LIB pure_quanta_power
J 0
(-2750 5925);
DISPLAY INVISIBLE (-2750 5925);
FORCEADD DNS..1
(-5575 1225);
PAINT RED (-5575 1225);
FORCEPROP 1 LAST COMMENT_BODY TRUE
R 1
J 0
(-5500 1000);
DISPLAY 0.872340 (-5500 1000);
PAINT GREEN (-5500 1000);
DISPLAY INVISIBLE (-5500 1000);
FORCEPROP 2 LAST CDS_LIB mstr_misc
J 0
(-5575 1225);
DISPLAY INVISIBLE (-5575 1225);
FORCEADD DNS..1
(-8225 1375);
PAINT RED (-8225 1375);
FORCEPROP 1 LAST COMMENT_BODY TRUE
R 1
J 0
(-8150 1150);
DISPLAY 0.872340 (-8150 1150);
PAINT GREEN (-8150 1150);
DISPLAY INVISIBLE (-8150 1150);
FORCEPROP 2 LAST CDS_LIB mstr_misc
J 0
(-8225 1375);
DISPLAY INVISIBLE (-8225 1375);
FORCEADD DNS..1
(-7975 6150);
PAINT RED (-7975 6150);
FORCEPROP 1 LAST COMMENT_BODY TRUE
R 1
J 0
(-7900 5925);
DISPLAY 0.872340 (-7900 5925);
PAINT GREEN (-7900 5925);
DISPLAY INVISIBLE (-7900 5925);
FORCEPROP 2 LAST CDS_LIB mstr_misc
J 0
(-7975 6150);
DISPLAY INVISIBLE (-7975 6150);
FORCEADD DNS..1
(-5375 575);
PAINT RED (-5375 575);
FORCEPROP 1 LAST COMMENT_BODY TRUE
R 1
J 0
(-5300 350);
DISPLAY 0.872340 (-5300 350);
PAINT GREEN (-5300 350);
DISPLAY INVISIBLE (-5300 350);
FORCEPROP 2 LAST CDS_LIB mstr_misc
J 0
(-5375 575);
DISPLAY INVISIBLE (-5375 575);
FORCEADD DNS..1
(-5625 6475);
PAINT RED (-5625 6475);
FORCEPROP 1 LAST COMMENT_BODY TRUE
R 1
J 0
(-5550 6250);
DISPLAY 0.872340 (-5550 6250);
PAINT GREEN (-5550 6250);
DISPLAY INVISIBLE (-5550 6250);
FORCEPROP 2 LAST CDS_LIB mstr_misc
J 0
(-5625 6475);
DISPLAY INVISIBLE (-5625 6475);
FORCEADD DNS..1
(-8250 5225);
PAINT RED (-8250 5225);
FORCEPROP 1 LAST COMMENT_BODY TRUE
R 1
J 0
(-8175 5000);
DISPLAY 0.872340 (-8175 5000);
PAINT GREEN (-8175 5000);
DISPLAY INVISIBLE (-8175 5000);
FORCEPROP 2 LAST CDS_LIB mstr_misc
J 0
(-8250 5225);
DISPLAY INVISIBLE (-8250 5225);
FORCEADD DNS..1
(-8450 5200);
PAINT RED (-8450 5200);
FORCEPROP 1 LAST COMMENT_BODY TRUE
R 1
J 0
(-8375 4975);
DISPLAY 0.872340 (-8375 4975);
PAINT GREEN (-8375 4975);
DISPLAY INVISIBLE (-8375 4975);
FORCEPROP 2 LAST CDS_LIB mstr_misc
J 0
(-8450 5200);
DISPLAY INVISIBLE (-8450 5200);
FORCEADD DNS..1
(-7825 5175);
PAINT RED (-7825 5175);
FORCEPROP 1 LAST COMMENT_BODY TRUE
R 1
J 0
(-7750 4950);
DISPLAY 0.872340 (-7750 4950);
PAINT GREEN (-7750 4950);
DISPLAY INVISIBLE (-7750 4950);
FORCEPROP 2 LAST CDS_LIB mstr_misc
J 0
(-7825 5175);
DISPLAY INVISIBLE (-7825 5175);
FORCEADD DNS..1
(-8050 5175);
PAINT RED (-8050 5175);
FORCEPROP 1 LAST COMMENT_BODY TRUE
R 1
J 0
(-7975 4950);
DISPLAY 0.872340 (-7975 4950);
PAINT GREEN (-7975 4950);
DISPLAY INVISIBLE (-7975 4950);
FORCEPROP 2 LAST CDS_LIB mstr_misc
J 0
(-8050 5175);
DISPLAY INVISIBLE (-8050 5175);
FORCEADD DNS..1
(-8550 6200);
PAINT RED (-8550 6200);
FORCEPROP 1 LAST COMMENT_BODY TRUE
R 1
J 0
(-8475 5975);
DISPLAY 0.872340 (-8475 5975);
PAINT GREEN (-8475 5975);
DISPLAY INVISIBLE (-8475 5975);
FORCEPROP 2 LAST CDS_LIB mstr_misc
J 0
(-8550 6200);
DISPLAY INVISIBLE (-8550 6200);
FORCEADD DNS..1
(-7750 6150);
PAINT RED (-7750 6150);
FORCEPROP 1 LAST COMMENT_BODY TRUE
R 1
J 0
(-7675 5925);
DISPLAY 0.872340 (-7675 5925);
PAINT GREEN (-7675 5925);
DISPLAY INVISIBLE (-7675 5925);
FORCEPROP 2 LAST CDS_LIB mstr_misc
J 0
(-7750 6150);
DISPLAY INVISIBLE (-7750 6150);
FORCEADD DNS..1
(-8175 6150);
PAINT RED (-8175 6150);
FORCEPROP 1 LAST COMMENT_BODY TRUE
R 1
J 0
(-8100 5925);
DISPLAY 0.872340 (-8100 5925);
PAINT GREEN (-8100 5925);
DISPLAY INVISIBLE (-8100 5925);
FORCEPROP 2 LAST CDS_LIB mstr_misc
J 0
(-8175 6150);
DISPLAY INVISIBLE (-8175 6150);
FORCEADD QUANTA_TITLE_BLOCK_C..1
(350 75);
FORCEPROP 0 LAST CDS_CON_LAST_MODIFIED Thu Sep 14 16:12:40 2023
J 0
(-1535 90);
DISPLAY INVISIBLE (-1535 90);
FORCEPROP 1 LAST CUSTOM_TXT_CDS <CON_LAST_MODIFIED>
J 0
(-1535 90);
DISPLAY 0.978723 (-1535 90);
FORCEPROP 2 LAST CUSTOM_TXT_CDS <XR_PAGE_TITLE>
J 0
(-7540 5325);
DISPLAY 0.638298 (-7540 5325);
PAINT PINK (-7540 5325);
DISPLAY INVISIBLE (-7540 5325);
FORCEPROP 1 LAST CUSTOM_TXT_CDS <NAME_2>
J 0
(-2825 125);
FORCEPROP 1 LAST CUSTOM_TXT_CDS <NAME_1>
J 0
(-2825 250);
FORCEPROP 1 LAST CUSTOM_TXT_CDS <Q_NUMBER>
J 0
(-1053 178);
DISPLAY 1.212766 (-1053 178);
FORCEPROP 1 LAST CUSTOM_TXT_CDS <Q_PROJ>
J 0
(-2032 177);
DISPLAY 1.212766 (-2032 177);
FORCEPROP 1 LAST CUSTOM_TXT_CDS <Q_REV>
J 0
(166 178);
DISPLAY 1.212766 (166 178);
FORCEPROP 1 LAST CUSTOM_TXT_CDS <CON_PAGE_NUM> OF <CON_TOTAL_PAGES>
J 0
(-96 93);
DISPLAY 0.978723 (-96 93);
FORCEPROP 1 LAST Q_TITLE PVDDCR_CPU1_P0/PVDDIO_P0 VR CONTROLLER
J 0
(-9000 125);
DISPLAY 2.446809 (-9000 125);
PAINT GREEN (-9000 125);
FORCEPROP 1 LAST COMMENT_BODY TRUE
J 0
(362 62);
DISPLAY 0.978723 (362 62);
PAINT GREEN (362 62);
DISPLAY INVISIBLE (362 62);
FORCEPROP 1 LAST Q_DEPT BU9
J 1
(-3413 124);
DISPLAY 1.957447 (-3413 124);
PAINT GREEN (-3413 124);
DISPLAY INVISIBLE (-3413 124);
FORCEPROP 2 LAST CDS_XR_PAGE_TITLE CR-200 : @T6G_MB_LIB.T6G(SCH_1):PAGE200
J 0
(-7540 5325);
DISPLAY 0.638298 (-7540 5325);
PAINT PINK (-7540 5325);
DISPLAY INVISIBLE (-7540 5325);
FORCEPROP 2 LAST PAGE_BORDER TRUE
J 0
(-7540 5325);
DISPLAY 0.638298 (-7540 5325);
PAINT PINK (-7540 5325);
DISPLAY INVISIBLE (-7540 5325);
FORCEPROP 2 LAST CDS_LIB pure_quanta
J 0
(350 75);
DISPLAY INVISIBLE (350 75);
FORCEPROP 1 LAST CDS_LMAN_SYM_OUTLINE -9475,6775,100,-125
J 0
(350 75);
DISPLAY 0.468085 (350 75);
PAINT GREEN (350 75);
DISPLAY INVISIBLE (350 75);
WIRE 16 -1 (-7075 950)(-7325 950);
WIRE 16 -1 (-6850 1200)(-6475 1200);
WIRE 16 -1 (-6850 1200)(-6850 1250);
WIRE 16 -1 (-2575 3100)(-2225 3100);
WIRE 16 -1 (-2225 3100)(-2225 3075);
WIRE 16 -1 (-2575 3400)(-2225 3400);
WIRE 16 -1 (-2225 3400)(-2225 3375);
WIRE 16 -1 (-6100 4575)(-6100 4525);
WIRE 16 -1 (-7375 1175)(-7525 1175);
WIRE 16 -1 (-7350 6375)(-7500 6375);
WIRE 16 -1 (-6625 2675)(-6625 2625);
WIRE 16 -1 (-6625 2675)(-7050 2675);
WIRE 16 -1 (-6625 3775)(-6625 3725);
WIRE 16 -1 (-6625 3775)(-7050 3775);
WIRE 16 -1 (-6900 6450)(-6575 6450);
WIRE 16 -1 (-6900 6450)(-6900 6500);
WIRE 16 -1 (-5400 475)(-5400 425);
WIRE 16 -1 (-5075 425)(-5075 475);
WIRE 16 -1 (-5325 1925)(-5075 1925);
WIRE 16 -1 (-5475 1200)(-4925 1200);
WIRE 16 -1 (-2750 725)(-2750 825);
WIRE 16 -1 (-2750 1300)(-2750 1400);
WIRE 16 -1 (-5550 6025)(-4975 6025);
WIRE 16 -1 (-5525 6450)(-4975 6450);
WIRE 16 -1 (-3075 5575)(-3075 5500);
WIRE 16 -1 (-3075 6050)(-3075 5975);
WIRE 16 -1 (-2750 5500)(-2750 5550);
WIRE 16 -1 (-2750 6025)(-2750 5975);
WIRE 17 273 (-8550 3850)(-8550 4400);
WIRE 17 273 (-8550 3850)(-8200 3850);
WIRE 17 273 (-8550 4400)(-8200 4400);
WIRE 17 273 (-8200 4400)(-8200 3850);
WIRE 16 -1 (-8300 4300)(-7400 4300);
FORCEPROP 2 LAST SIG_NAME VSENSE_PVDDCR_CPU1_P0_DP
J 0
(-7985 4310);
DISPLAY 0.489362 (-7985 4310);
WIRE 16 -1 (-6225 4300)(-7400 4300);
WIRE 16 -1 (-7400 4450)(-7400 4300);
WIRE 16 -1 (-7400 4450)(-7200 4450);
WIRE 16 -1 (-7400 3925)(-5675 3925);
WIRE 16 -1 (-7400 3775)(-7400 3925);
WIRE 16 -1 (-7400 3925)(-8300 3925);
FORCEPROP 2 LAST SIG_NAME VSENSE_VSS_SENSE_C_P0
J 2
(-7510 3935);
DISPLAY 0.489362 (-7510 3935);
WIRE 16 -1 (-4975 3925)(-5675 3925);
WIRE 16 -1 (-5675 4025)(-5675 3925);
WIRE 16 -1 (-4975 3925)(-4975 4000);
WIRE 16 -1 (-7400 3775)(-7250 3775);
WIRE 16 -1 (-4800 4000)(-4975 4000);
WIRE 16 -1 (-8425 4900)(-8250 4900);
WIRE 16 -1 (-8425 5100)(-8425 4900);
WIRE 16 -1 (-8425 4900)(-8650 4900);
WIRE 16 -1 (-8250 4900)(-8075 4900);
WIRE 16 -1 (-8250 5100)(-8250 4900);
WIRE 16 -1 (-8075 4900)(-7825 4900);
WIRE 16 -1 (-8075 5100)(-8075 4900);
WIRE 16 -1 (-8650 5100)(-8650 4900);
WIRE 16 -1 (-8650 4900)(-8650 4800);
WIRE 16 -1 (-7825 4900)(-7825 5100);
WIRE 16 -1 (-6425 4550)(-6425 4450);
WIRE 16 -1 (-6425 4450)(-7000 4450);
WIRE 16 -1 (-2775 3400)(-3450 3400);
FORCEPROP 2 LAST SIG_NAME NC_PVDDCR_CPU1_P0_IMON7
J 0
(-3310 3410);
DISPLAY 0.489362 (-3310 3410);
FORCEPROP 2 LASTPROP $XRERR UNIQUE?
J 0
(-3550 3410);
DISPLAY 0.638298 (-3550 3410);
PAINT MONO (-3550 3410);
DISPLAY INVISIBLE (-3550 3410);
WIRE 16 -1 (-6950 1700)(-6950 1725);
WIRE 16 -1 (-5750 1725)(-6950 1725);
WIRE 16 -1 (-6950 1725)(-6950 1775);
WIRE 16 -1 (-5750 1725)(-5750 1550);
WIRE 16 -1 (-4800 1550)(-5750 1550);
FORCEPROP 2 LAST SIG_NAME PVDDCR_CPU1_P0_EN1_ADDR_CFG
J 0
(-5535 1560);
DISPLAY 0.489362 (-5535 1560);
FORCEPROP 2 LASTPROP $XRERR UNIQUE?
J 0
(-5775 1560);
DISPLAY 0.638298 (-5775 1560);
PAINT MONO (-5775 1560);
DISPLAY INVISIBLE (-5775 1560);
WIRE 16 -1 (-6275 1050)(-5900 1050);
WIRE 16 -1 (-5900 1050)(-4800 1050);
FORCEPROP 2 LAST SIG_NAME PWRGD_PVDDIO_P0_R
J 0
(-5325 1060);
DISPLAY 0.489362 (-5325 1060);
FORCEPROP 2 LASTPROP $XRERR UNIQUE?
J 0
(-5565 1060);
DISPLAY 0.638298 (-5565 1060);
PAINT MONO (-5565 1060);
DISPLAY INVISIBLE (-5565 1060);
WIRE 16 -1 (-5900 1200)(-5900 1050);
WIRE 16 -1 (-5675 1200)(-5900 1200);
WIRE 16 -1 (-5900 1200)(-6275 1200);
WIRE 16 -1 (-6875 950)(-6650 950);
WIRE 16 -1 (-6200 950)(-6650 950);
WIRE 16 -1 (-6650 875)(-6650 950);
WIRE 16 -1 (-4800 950)(-6200 950);
FORCEPROP 2 LAST SIG_NAME PVDDCR_CPU1_P0_VMON
J 0
(-5325 960);
DISPLAY 0.489362 (-5325 960);
FORCEPROP 2 LASTPROP $XRERR UNIQUE?
J 0
(-5565 960);
DISPLAY 0.638298 (-5565 960);
PAINT MONO (-5565 960);
DISPLAY INVISIBLE (-5565 960);
WIRE 16 -1 (-6200 900)(-6200 950);
WIRE 16 -1 (-4800 2900)(-4975 2900);
WIRE 16 -1 (-4975 2825)(-4975 2900);
WIRE 16 -1 (-4975 2825)(-5625 2825);
WIRE 16 -1 (-5625 2925)(-5625 2825);
WIRE 16 -1 (-7375 2825)(-5625 2825);
WIRE 16 -1 (-7375 2675)(-7375 2825);
WIRE 16 -1 (-8300 2825)(-7375 2825);
FORCEPROP 2 LAST SIG_NAME VSENSE_VSS_SENSE_B_P0
J 0
(-7885 2835);
DISPLAY 0.489362 (-7885 2835);
WIRE 16 -1 (-7375 2675)(-7250 2675);
WIRE 16 -1 (-5975 3200)(-5625 3200);
WIRE 16 -1 (-4975 3200)(-5625 3200);
FORCEPROP 2 LAST SIG_NAME VSENSE_PVDDIO_P0_VSEN1
J 0
(-5435 3210);
DISPLAY 0.489362 (-5435 3210);
FORCEPROP 2 LASTPROP $XRERR UNIQUE?
J 0
(-5675 3210);
DISPLAY 0.638298 (-5675 3210);
PAINT MONO (-5675 3210);
DISPLAY INVISIBLE (-5675 3210);
WIRE 16 -1 (-5625 3125)(-5625 3200);
WIRE 16 -1 (-4975 3200)(-4975 3150);
WIRE 16 -1 (-4975 3150)(-4800 3150);
WIRE 16 -1 (-7600 2175)(-7600 2075);
WIRE 16 -1 (-7250 2075)(-7600 2075);
FORCEPROP 2 LAST SIG_NAME PVDDIO_P0_EN_G
J 0
(-7585 2035);
DISPLAY 0.489362 (-7585 2035);
FORCEPROP 2 LASTPROP $XRERR UNIQUE?
J 0
(-7825 2035);
DISPLAY 0.638298 (-7825 2035);
PAINT MONO (-7825 2035);
DISPLAY INVISIBLE (-7825 2035);
WIRE 16 -1 (-7600 1850)(-7600 2075);
WIRE 16 -1 (-6950 2375)(-6950 2475);
WIRE 16 -1 (-6950 2475)(-7600 2475);
WIRE 16 -1 (-7600 2375)(-7600 2475);
WIRE 16 -1 (-7600 2475)(-7600 2525);
WIRE 16 -1 (-8225 1650)(-8000 1650);
FORCEPROP 2 LAST SIG_NAME PVDDIO_P0_EN_R
J 0
(-8185 1660);
DISPLAY 0.489362 (-8185 1660);
FORCEPROP 2 LASTPROP $XRERR UNIQUE?
J 0
(-8425 1660);
DISPLAY 0.638298 (-8425 1660);
PAINT MONO (-8425 1660);
DISPLAY INVISIBLE (-8425 1660);
WIRE 16 -1 (-8250 1650)(-8225 1650);
WIRE 16 -1 (-8225 1650)(-8225 1500);
WIRE 16 -1 (-7750 1650)(-8000 1650);
WIRE 16 -1 (-8000 1650)(-8000 1525);
WIRE 16 -1 (-8575 5850)(-7825 5850);
WIRE 16 -1 (-7825 5850)(-7750 5850);
WIRE 16 -1 (-7825 5300)(-7825 5850);
WIRE 16 -1 (-7750 5850)(-6575 5850);
FORCEPROP 2 LAST SIG_NAME SVID_PVDDCR_CPU1_P0_SVC_R
J 0
(-7410 5885);
DISPLAY 0.489362 (-7410 5885);
WIRE 16 -1 (-7750 6075)(-7750 5850);
WIRE 16 -1 (-8575 5700)(-8075 5700);
WIRE 16 -1 (-8075 5700)(-8000 5700);
WIRE 16 -1 (-8075 5300)(-8075 5700);
WIRE 16 -1 (-6600 5700)(-8000 5700);
FORCEPROP 2 LAST SIG_NAME SVID_PVDDCR_CPU1_P0_SVD_R
J 0
(-7410 5710);
DISPLAY 0.489362 (-7410 5710);
WIRE 16 -1 (-8000 6075)(-8000 5700);
WIRE 16 -1 (-5825 1925)(-5825 2050);
WIRE 16 -1 (-5525 1925)(-5825 1925);
WIRE 16 -1 (-5825 1925)(-5975 1925);
WIRE 16 -1 (-4800 2050)(-5825 2050);
WIRE 16 -1 (-5825 2175)(-5825 2050);
WIRE 16 -1 (-5275 2175)(-5825 2175);
WIRE 16 -1 (-5975 1925)(-5975 1950);
WIRE 16 -1 (-8200 6075)(-8200 5550);
WIRE 16 -1 (-8200 5550)(-6575 5550);
FORCEPROP 2 LAST SIG_NAME SVID_PVDDCR_CPU1_P0_SVTO
J 0
(-7435 5560);
DISPLAY 0.489362 (-7435 5560);
WIRE 16 -1 (-8250 5550)(-8200 5550);
WIRE 16 -1 (-8425 5550)(-8250 5550);
WIRE 16 -1 (-8250 5300)(-8250 5550);
WIRE 16 -1 (-8425 5300)(-8425 5550);
WIRE 16 -1 (-8575 5550)(-8425 5550);
WIRE 16 -1 (-6775 6375)(-6775 6300);
WIRE 16 -1 (-6775 6375)(-7150 6375);
WIRE 16 -1 (-6775 6300)(-6575 6300);
WIRE 16 -1 (-7225 6300)(-6775 6300);
FORCEPROP 2 LAST SIG_NAME PWRGD_PVDDCR_CPU1_P0
J 0
(-7185 6310);
DISPLAY 0.489362 (-7185 6310);
WIRE 16 -1 (-7225 6150)(-6575 6150);
FORCEPROP 2 LAST SIG_NAME FM_PVDDCR_CPU1_P0_EN
J 0
(-7185 6160);
DISPLAY 0.489362 (-7185 6160);
WIRE 16 -1 (-6100 4850)(-5850 4850);
WIRE 16 -1 (-6100 4850)(-6100 4775);
WIRE 16 -1 (-6750 4850)(-6100 4850);
FORCEPROP 2 LAST SIG_NAME PVDDCR_CPU1_P0_SMB_ALERT
J 0
(-6735 4860);
DISPLAY 0.489362 (-6735 4860);
WIRE 16 -1 (-6800 1175)(-6800 1100);
WIRE 16 -1 (-6800 1175)(-7175 1175);
WIRE 16 -1 (-6700 1100)(-6800 1100);
WIRE 16 -1 (-6800 1100)(-7475 1100);
FORCEPROP 2 LAST SIG_NAME PWRGD_PVDDIO_P0
J 0
(-7460 1110);
DISPLAY 0.489362 (-7460 1110);
WIRE 16 -1 (-6700 1050)(-6700 1100);
WIRE 16 -1 (-6475 1050)(-6700 1050);
WIRE 16 -1 (-8750 1650)(-8450 1650);
FORCEPROP 2 LAST SIG_NAME PVDDIO_P0_EN
J 0
(-8760 1660);
DISPLAY 0.489362 (-8760 1660);
WIRE 16 -1 (-6400 2300)(-5825 2300);
FORCEPROP 2 LAST SIG_NAME PVDDCR_CPU1_P0_OCP_N
J 0
(-6385 2310);
DISPLAY 0.489362 (-6385 2310);
WIRE 17 273 (-8575 2750)(-8575 3300);
WIRE 17 273 (-8575 2750)(-8250 2750);
WIRE 17 273 (-8575 3300)(-8250 3300);
WIRE 17 273 (-8250 3300)(-8250 2750);
WIRE 16 -1 (-6750 5000)(-5850 5000);
FORCEPROP 2 LAST SIG_NAME SMB_SCM_2_R5_SDA
J 0
(-6535 5010);
DISPLAY 0.489362 (-6535 5010);
WIRE 17 273 (-8850 725)(-7650 725);
WIRE 17 273 (-8850 725)(-8850 325);
WIRE 17 273 (-7650 725)(-7650 325);
WIRE 17 273 (-8850 325)(-7650 325);
WIRE 16 -1 (-6400 2450)(-5825 2450);
FORCEPROP 2 LAST SIG_NAME PVDDCR_CPU1_P0_RESET_N
J 0
(-6385 2460);
DISPLAY 0.489362 (-6385 2460);
WIRE 16 -1 (-8650 5400)(-8550 5400);
WIRE 16 -1 (-8650 5400)(-8650 5300);
WIRE 16 -1 (-8550 5400)(-6575 5400);
FORCEPROP 2 LAST SIG_NAME SVID_PVDDCR_CPU1_P0_SVTI
J 0
(-7435 5425);
DISPLAY 0.489362 (-7435 5425);
FORCEPROP 2 LASTPROP $XRERR UNIQUE?
J 0
(-7675 5425);
DISPLAY 0.638298 (-7675 5425);
PAINT MONO (-7675 5425);
DISPLAY INVISIBLE (-7675 5425);
WIRE 16 -1 (-8550 6075)(-8550 5400);
WIRE 16 -1 (-3450 4900)(-2350 4900);
FORCEPROP 2 LAST SIG_NAME PVDDCR_CPU1_P0_IMON2
J 0
(-3260 4910);
DISPLAY 0.489362 (-3260 4910);
WIRE 16 -1 (-3450 5000)(-2350 5000);
FORCEPROP 2 LAST SIG_NAME PVDDCR_CPU1_P0_PWM2
J 0
(-3260 5010);
DISPLAY 0.489362 (-3260 5010);
WIRE 16 -1 (-3450 4600)(-2350 4600);
FORCEPROP 2 LAST SIG_NAME PVDDCR_CPU1_P0_IMON3
J 0
(-3260 4610);
DISPLAY 0.489362 (-3260 4610);
WIRE 16 -1 (-3450 4700)(-2350 4700);
FORCEPROP 2 LAST SIG_NAME PVDDCR_CPU1_P0_PWM3
J 0
(-3260 4710);
DISPLAY 0.489362 (-3260 4710);
WIRE 16 -1 (-3450 4300)(-2350 4300);
FORCEPROP 2 LAST SIG_NAME PVDDCR_CPU1_P0_IMON4
J 0
(-3260 4310);
DISPLAY 0.489362 (-3260 4310);
WIRE 16 -1 (-3450 4400)(-2350 4400);
FORCEPROP 2 LAST SIG_NAME PVDDCR_CPU1_P0_PWM4
J 0
(-3260 4410);
DISPLAY 0.489362 (-3260 4410);
WIRE 16 -1 (-3450 4000)(-2350 4000);
FORCEPROP 2 LAST SIG_NAME PVDDCR_CPU1_P0_IMON5
J 0
(-3260 4010);
DISPLAY 0.489362 (-3260 4010);
WIRE 16 -1 (-3450 4100)(-2350 4100);
FORCEPROP 0 LAST SIG_NAME PVDDCR_CPU1_P0_PWM5
J 0
(-3260 4110);
DISPLAY 0.489362 (-3260 4110);
WIRE 16 -1 (-2350 1900)(-3450 1900);
FORCEPROP 2 LAST SIG_NAME PVDDIO_P0_IMON1
J 0
(-3260 1910);
DISPLAY 0.489362 (-3260 1910);
WIRE 16 -1 (-3450 2000)(-2350 2000);
FORCEPROP 2 LAST SIG_NAME PVDDIO_P0_PWM1
J 0
(-3260 2010);
DISPLAY 0.489362 (-3260 2010);
WIRE 16 -1 (-3200 1400)(-3450 1400);
WIRE 16 -1 (-3200 1700)(-3200 1400);
WIRE 16 -1 (-2750 1700)(-3200 1700);
FORCEPROP 2 LAST SIG_NAME PVDDIO_P0_TEMP1
J 0
(-3110 1710);
DISPLAY 0.489362 (-3110 1710);
WIRE 16 -1 (-2750 1700)(-2200 1700);
WIRE 16 -1 (-2750 1700)(-2750 1600);
WIRE 16 -1 (-5075 2175)(-4925 2175);
WIRE 16 -1 (-4925 2175)(-4925 2300);
WIRE 16 -1 (-4800 2300)(-4925 2300);
FORCEPROP 2 LAST SIG_NAME PVDDCR_CPU1_P0_OCP_N_R
J 0
(-5385 2310);
DISPLAY 0.489362 (-5385 2310);
FORCEPROP 2 LASTPROP $XRERR UNIQUE?
J 0
(-5625 2310);
DISPLAY 0.638298 (-5625 2310);
PAINT MONO (-5625 2310);
DISPLAY INVISIBLE (-5625 2310);
WIRE 16 -1 (-5625 2300)(-4925 2300);
WIRE 16 -1 (-2350 2500)(-3450 2500);
FORCEPROP 2 LAST SIG_NAME PVDDIO_P0_IMON3
J 0
(-3260 2510);
DISPLAY 0.489362 (-3260 2510);
WIRE 16 -1 (-3450 5300)(-2350 5300);
FORCEPROP 2 LAST SIG_NAME PVDDCR_CPU1_P0_PWM1
J 0
(-3260 5310);
DISPLAY 0.489362 (-3260 5310);
WIRE 16 -1 (-2350 2200)(-3450 2200);
FORCEPROP 2 LAST SIG_NAME PVDDIO_P0_IMON2
J 0
(-3260 2210);
DISPLAY 0.489362 (-3260 2210);
WIRE 16 -1 (-2200 1100)(-2750 1100);
FORCEPROP 2 LAST SIG_NAME PVDDCR_CPU1_P0_TEMP0
J 0
(-3135 1110);
DISPLAY 0.489362 (-3135 1110);
WIRE 16 -1 (-2750 1100)(-2750 1025);
WIRE 16 -1 (-2750 1100)(-3450 1100);
WIRE 16 -1 (-4800 850)(-5075 850);
WIRE 16 -1 (-5075 775)(-5075 850);
FORCEPROP 2 LAST SIG_NAME PVDDCR_CPU1_P0_VINSEN
J 0
(-5360 875);
DISPLAY 0.489362 (-5360 875);
FORCEPROP 2 LASTPROP $XRERR UNIQUE?
J 0
(-5600 875);
DISPLAY 0.638298 (-5600 875);
PAINT MONO (-5600 875);
DISPLAY INVISIBLE (-5600 875);
WIRE 16 -1 (-5075 675)(-5075 775);
WIRE 16 -1 (-5400 775)(-5075 775);
WIRE 16 -1 (-5400 675)(-5400 775);
WIRE 16 -1 (-5650 775)(-5400 775);
WIRE 16 -1 (-2750 5750)(-2750 5825);
WIRE 16 -1 (-2125 5825)(-2750 5825);
WIRE 16 -1 (-3075 5825)(-2750 5825);
WIRE 16 -1 (-3075 5825)(-3075 5775);
WIRE 16 -1 (-3275 5825)(-3075 5825);
FORCEPROP 2 LAST SIG_NAME PVDDCR_CPU1_P0_VCCS
J 0
(-3235 5835);
DISPLAY 0.489362 (-3235 5835);
WIRE 16 -1 (-3275 6000)(-3275 5825);
WIRE 16 -1 (-3450 6000)(-3275 6000);
WIRE 16 -1 (-3450 3800)(-2350 3800);
FORCEPROP 0 LAST SIG_NAME PVDDCR_CPU1_P0_PWM6
J 0
(-3260 3810);
DISPLAY 0.489362 (-3260 3810);
WIRE 16 -1 (-5725 6450)(-5950 6450);
WIRE 16 -1 (-5950 6300)(-5950 6450);
WIRE 16 -1 (-5950 6450)(-6375 6450);
WIRE 16 -1 (-5950 6300)(-4800 6300);
FORCEPROP 2 LAST SIG_NAME PWRGD_PVDDCR_CPU1_P0_R
J 0
(-5385 6310);
DISPLAY 0.489362 (-5385 6310);
FORCEPROP 2 LASTPROP $XRERR UNIQUE?
J 0
(-5625 6310);
DISPLAY 0.638298 (-5625 6310);
PAINT MONO (-5625 6310);
DISPLAY INVISIBLE (-5625 6310);
WIRE 16 -1 (-5950 6300)(-6375 6300);
WIRE 16 -1 (-3450 2300)(-2350 2300);
FORCEPROP 2 LAST SIG_NAME PVDDIO_P0_PWM2
J 0
(-3260 2310);
DISPLAY 0.489362 (-3260 2310);
WIRE 16 -1 (-6025 4300)(-5675 4300);
WIRE 16 -1 (-4975 4300)(-5675 4300);
FORCEPROP 2 LAST SIG_NAME VSENSE_PVDDCR_CPU1_P0_VSEN0
J 0
(-5560 4310);
DISPLAY 0.489362 (-5560 4310);
FORCEPROP 2 LASTPROP $XRERR UNIQUE?
J 0
(-5800 4310);
DISPLAY 0.638298 (-5800 4310);
PAINT MONO (-5800 4310);
DISPLAY INVISIBLE (-5800 4310);
WIRE 16 -1 (-5675 4225)(-5675 4300);
WIRE 16 -1 (-4975 4300)(-4975 4250);
WIRE 16 -1 (-4975 4250)(-4800 4250);
WIRE 16 -1 (-3450 3500)(-2350 3500);
FORCEPROP 2 LAST SIG_NAME NC_PVDDCR_CPU1_P0_PWM7
J 0
(-3285 3510);
DISPLAY 0.489362 (-3285 3510);
FORCEPROP 2 LASTPROP $XRERR UNIQUE?
J 0
(-2320 3500);
DISPLAY 0.638298 (-2320 3500);
PAINT MONO (-2320 3500);
DISPLAY INVISIBLE (-2320 3500);
WIRE 16 -1 (-5650 5000)(-4800 5000);
FORCEPROP 2 LAST SIG_NAME SMB_DIO_PVDDCR_CPU1_P0_R
J 0
(-5485 5010);
DISPLAY 0.489362 (-5485 5010);
FORCEPROP 2 LASTPROP $XRERR UNIQUE?
J 0
(-5725 5010);
DISPLAY 0.638298 (-5725 5010);
PAINT MONO (-5725 5010);
DISPLAY INVISIBLE (-5725 5010);
WIRE 16 -1 (-5750 6025)(-5950 6025);
WIRE 16 -1 (-5950 6150)(-5950 6025);
WIRE 16 -1 (-5950 6150)(-4800 6150);
FORCEPROP 2 LAST SIG_NAME PVDDCR_CPU1_P0_EN_R
J 0
(-5385 6160);
DISPLAY 0.489362 (-5385 6160);
FORCEPROP 2 LASTPROP $XRERR UNIQUE?
J 0
(-5625 6160);
DISPLAY 0.638298 (-5625 6160);
PAINT MONO (-5625 6160);
DISPLAY INVISIBLE (-5625 6160);
WIRE 16 -1 (-6375 6150)(-5950 6150);
WIRE 16 -1 (-5650 4850)(-4800 4850);
FORCEPROP 2 LAST SIG_NAME PVDDCR_CPU1_P0_SMB_ALERT_R
J 0
(-5485 4860);
DISPLAY 0.489362 (-5485 4860);
FORCEPROP 2 LASTPROP $XRERR UNIQUE?
J 0
(-5725 4860);
DISPLAY 0.638298 (-5725 4860);
PAINT MONO (-5725 4860);
DISPLAY INVISIBLE (-5725 4860);
WIRE 16 -1 (-6400 5700)(-4800 5700);
FORCEPROP 2 LAST SIG_NAME SVID_PVDDCR_CPU1_P0_SVD_R1
J 0
(-5585 5710);
DISPLAY 0.553191 (-5585 5710);
FORCEPROP 2 LASTPROP $XRERR UNIQUE?
J 0
(-5825 5710);
DISPLAY 0.638298 (-5825 5710);
PAINT MONO (-5825 5710);
DISPLAY INVISIBLE (-5825 5710);
WIRE 16 -1 (-2775 3100)(-3450 3100);
FORCEPROP 2 LAST SIG_NAME NC_PVDDCR_CPU1_P0_IMON8
J 0
(-3335 3100);
DISPLAY 0.489362 (-3335 3100);
FORCEPROP 2 LASTPROP $XRERR UNIQUE?
J 0
(-3575 3100);
DISPLAY 0.638298 (-3575 3100);
PAINT MONO (-3575 3100);
DISPLAY INVISIBLE (-3575 3100);
WIRE 16 -1 (-5625 2450)(-5525 2450);
WIRE 16 -1 (-4800 2450)(-5525 2450);
WIRE 16 -1 (-5525 2600)(-5525 2450);
FORCEPROP 2 LAST SIG_NAME PVDDCR_CPU1_P0_RESET_N_R
J 0
(-5460 2460);
DISPLAY 0.489362 (-5460 2460);
FORCEPROP 2 LASTPROP $XRERR UNIQUE?
J 0
(-5700 2460);
DISPLAY 0.638298 (-5700 2460);
PAINT MONO (-5700 2460);
DISPLAY INVISIBLE (-5700 2460);
WIRE 16 -1 (-5775 2600)(-5525 2600);
WIRE 16 -1 (-4800 5550)(-6375 5550);
FORCEPROP 2 LAST SIG_NAME SVID_PVDDCR_CPU1_P0_SVTO_R
J 0
(-5535 5560);
DISPLAY 0.489362 (-5535 5560);
FORCEPROP 2 LASTPROP $XRERR UNIQUE?
J 0
(-5775 5560);
DISPLAY 0.638298 (-5775 5560);
PAINT MONO (-5775 5560);
DISPLAY INVISIBLE (-5775 5560);
WIRE 16 -1 (-2375 3700)(-3450 3700);
FORCEPROP 2 LAST SIG_NAME PVDDCR_CPU1_P0_IMON6
J 0
(-3260 3710);
DISPLAY 0.489362 (-3260 3710);
WIRE 16 -1 (-4800 5850)(-6375 5850);
FORCEPROP 2 LAST SIG_NAME SVID_PVDDCR_CPU1_P0_SVC_R1
J 0
(-5585 5860);
DISPLAY 0.553191 (-5585 5860);
FORCEPROP 2 LASTPROP $XRERR UNIQUE?
J 0
(-5825 5860);
DISPLAY 0.638298 (-5825 5860);
PAINT MONO (-5825 5860);
DISPLAY INVISIBLE (-5825 5860);
WIRE 16 -1 (-5650 5150)(-4800 5150);
FORCEPROP 2 LAST SIG_NAME SMB_CLK_PVDDCR_CPU1_P0_R
J 0
(-5485 5160);
DISPLAY 0.489362 (-5485 5160);
FORCEPROP 2 LASTPROP $XRERR UNIQUE?
J 0
(-5725 5160);
DISPLAY 0.638298 (-5725 5160);
PAINT MONO (-5725 5160);
DISPLAY INVISIBLE (-5725 5160);
WIRE 16 -1 (-4800 5400)(-6375 5400);
FORCEPROP 2 LAST SIG_NAME SVID_PVDDCR_CPU1_P0_SVTI_R
J 0
(-5535 5410);
DISPLAY 0.489362 (-5535 5410);
FORCEPROP 2 LASTPROP $XRERR UNIQUE?
J 0
(-5775 5410);
DISPLAY 0.638298 (-5775 5410);
PAINT MONO (-5775 5410);
DISPLAY INVISIBLE (-5775 5410);
WIRE 16 -1 (-2400 6300)(-2750 6300);
WIRE 16 -1 (-2750 6225)(-2750 6300);
WIRE 16 -1 (-2750 6300)(-3075 6300);
WIRE 16 -1 (-3075 6300)(-3450 6300);
FORCEPROP 2 LAST SIG_NAME PVDDCR_CPU1_P0_VCC
J 0
(-3285 6310);
DISPLAY 0.489362 (-3285 6310);
FORCEPROP 2 LASTPROP $XRERR UNIQUE?
J 0
(-3525 6310);
DISPLAY 0.638298 (-3525 6310);
PAINT MONO (-3525 6310);
DISPLAY INVISIBLE (-3525 6310);
WIRE 16 -1 (-3075 6300)(-3075 6250);
WIRE 16 -1 (-6750 5150)(-5850 5150);
FORCEPROP 2 LAST SIG_NAME SMB_SCM_2_R5_SCL
J 0
(-6535 5160);
DISPLAY 0.489362 (-6535 5160);
WIRE 16 -1 (-3450 5200)(-2350 5200);
FORCEPROP 2 LAST SIG_NAME PVDDCR_CPU1_P0_IMON1
J 0
(-3260 5210);
DISPLAY 0.489362 (-3260 5210);
WIRE 17 273 (-1300 4250)(300 4250);
WIRE 17 273 (-1300 5300)(-1300 4250);
WIRE 17 273 (300 5300)(300 4250);
WIRE 17 273 (-1300 5300)(300 5300);
WIRE 16 -1 (-7375 3350)(-7200 3350);
WIRE 16 -1 (-7375 3200)(-7375 3350);
WIRE 16 -1 (-6175 3200)(-7375 3200);
WIRE 16 -1 (-7375 3200)(-8300 3200);
FORCEPROP 2 LAST SIG_NAME VSENSE_PVDDIO_P0_DP
J 0
(-7910 3210);
DISPLAY 0.489362 (-7910 3210);
WIRE 17 273 (-1300 6650)(300 6650);
WIRE 17 273 (-1300 6650)(-1300 5375);
WIRE 17 273 (300 6650)(300 5375);
WIRE 17 273 (-1300 5375)(300 5375);
WIRE 16 -1 (-3450 3200)(-2350 3200);
FORCEPROP 2 LAST SIG_NAME NC_PVDDCR_CPU1_P0_PWM8
J 0
(-3260 3210);
DISPLAY 0.489362 (-3260 3210);
FORCEPROP 2 LASTPROP $XRERR UNIQUE?
J 0
(-2320 3200);
DISPLAY 0.638298 (-2320 3200);
PAINT MONO (-2320 3200);
DISPLAY INVISIBLE (-2320 3200);
WIRE 16 -1 (-3450 2900)(-2375 2900);
FORCEPROP 2 LAST SIG_NAME PVDDIO_P0_PWM4
J 0
(-3260 2910);
DISPLAY 0.489362 (-3260 2910);
WIRE 16 -1 (-3450 2600)(-2350 2600);
FORCEPROP 0 LAST SIG_NAME PVDDIO_P0_PWM3
J 0
(-3260 2610);
DISPLAY 0.489362 (-3260 2610);
WIRE 16 -1 (-6950 1475)(-6950 1500);
WIRE 16 -1 (-7600 1475)(-6950 1475);
WIRE 16 -1 (-7600 1550)(-7600 1475);
WIRE 16 -1 (-7600 1475)(-7600 1425);
WIRE 16 -1 (-6325 2600)(-5975 2600);
WIRE 16 -1 (-6325 2675)(-6325 2600);
WIRE 16 -1 (-4850 750)(-4800 750);
WIRE 16 -1 (-4850 675)(-4850 750);
WIRE 16 -1 (-5925 775)(-5850 775);
WIRE 16 -1 (-5925 800)(-5925 775);
WIRE 16 -1 (-6650 675)(-6650 575);
WIRE 16 -1 (-6650 575)(-6200 575);
WIRE 16 -1 (-6200 700)(-6200 575);
WIRE 16 -1 (-6200 575)(-6200 525);
WIRE 16 -1 (-8200 6425)(-8000 6425);
WIRE 16 -1 (-8200 6425)(-8200 6275);
WIRE 16 -1 (-8550 6425)(-8200 6425);
WIRE 16 -1 (-8000 6425)(-7750 6425);
WIRE 16 -1 (-8000 6275)(-8000 6425);
WIRE 16 -1 (-7750 6425)(-7750 6275);
WIRE 16 -1 (-8550 6275)(-8550 6425);
WIRE 16 -1 (-8550 6425)(-8550 6475);
WIRE 16 -1 (-8225 1300)(-8225 1275);
WIRE 16 -1 (-8225 1275)(-8000 1275);
WIRE 16 -1 (-8000 1325)(-8000 1275);
WIRE 16 -1 (-8000 1275)(-8000 1225);
WIRE 16 -1 (-6600 3450)(-6600 3350);
WIRE 16 -1 (-6600 3350)(-7000 3350);
WIRE 16 -1 (-1775 6375)(-1775 6300);
WIRE 16 -1 (-1775 6300)(-2200 6300);
WIRE 16 -1 (-2375 2800)(-3450 2800);
FORCEPROP 2 LAST SIG_NAME PVDDIO_P0_IMON4
J 0
(-3260 2810);
DISPLAY 0.489362 (-3260 2810);
CIRCLE (-6225 4225)(-6045 4225);
PAINT YELLOW (-6225 4225);
CIRCLE (-8725 5100)(-8565 5100);
PAINT YELLOW (-8725 5100);
DOT 1 (-5950 6300);
DOT 1 (-5825 2050);
DOT 1 (-5525 2450);
DOT 1 (-2750 1700);
DOT 1 (-5625 3200);
DOT 1 (-8650 4900);
DOT 1 (-6775 6300);
DOT 1 (-6800 1100);
DOT 1 (-6100 4850);
DOT 1 (-8225 1650);
DOT 1 (-8000 1650);
DOT 1 (-5675 4300);
DOT 1 (-2750 6300);
DOT 1 (-3075 6300);
DOT 1 (-2750 5825);
DOT 1 (-3075 5825);
DOT 1 (-5950 6450);
DOT 1 (-2750 1100);
DOT 1 (-4925 2300);
DOT 1 (-5625 2825);
DOT 1 (-5075 775);
DOT 1 (-5400 775);
DOT 1 (-5825 1925);
DOT 1 (-5900 1200);
DOT 1 (-5900 1050);
DOT 1 (-6200 950);
DOT 1 (-6200 575);
DOT 1 (-8000 6425);
DOT 1 (-8200 6425);
DOT 1 (-8550 6425);
DOT 1 (-7400 4300);
DOT 1 (-7825 5850);
DOT 1 (-8075 5700);
DOT 1 (-8200 5550);
DOT 1 (-8250 5550);
DOT 1 (-8425 5550);
DOT 1 (-8550 5400);
DOT 1 (-8075 4900);
DOT 1 (-8250 4900);
DOT 1 (-8425 4900);
DOT 1 (-7400 3925);
DOT 1 (-7375 3200);
DOT 1 (-7375 2825);
DOT 1 (-6950 1725);
DOT 1 (-7600 1475);
DOT 1 (-6650 950);
DOT 1 (-8000 1275);
DOT 1 (-5950 6150);
DOT 1 (-7750 5850);
DOT 1 (-8000 5700);
CIRCLE (-6175 3275)(-5995 3275);
PAINT YELLOW (-6175 3275);
DOT 1 (-5675 3925);
DOT 1 (-7600 2475);
DOT 1 (-7600 2075);
FORCENOTE
PMBUS ADDRESS AND CONFIG
(-8875 775) 0;
DISPLAY LEFT (-8875 775);
DISPLAY 1.170213 (-8875 775);
PAINT WHITE (-8875 775);
FORCENOTE
ADDRESS(7-BIT)
(-8550 650) 0;
DISPLAY LEFT (-8550 650);
DISPLAY 0.808511 (-8550 650);
PAINT WHITE (-8550 650);
FORCENOTE
0X62
(-8325 550) 0;
DISPLAY LEFT (-8325 550);
DISPLAY 0.638298 (-8325 550);
PAINT WHITE (-8325 550);
FORCENOTE
1/1.96K
(-7975 550) 0;
DISPLAY LEFT (-7975 550);
DISPLAY 0.638298 (-7975 550);
PAINT WHITE (-7975 550);
FORCENOTE
PU12 = TBD/MP2857GQKT-001B-Z
(-1250 1875) 0;
DISPLAY LEFT (-1250 1875);
DISPLAY 1.021277 (-1250 1875);
PAINT WHITE (-1250 1875);
FORCENOTE
BOM NOTE
(-1250 3375) 0;
DISPLAY LEFT (-1250 3375);
DISPLAY 1.595745 (-1250 3375);
PAINT WHITE (-1250 3375);
FORCENOTE
3RD SOURCE:MPS BOM
(-1250 1975) 0;
DISPLAY LEFT (-1250 1975);
DISPLAY 1.276596 (-1250 1975);
PAINT WHITE (-1250 1975);
FORCENOTE
PR53,PC67 = EMPTY
(-1250 1800) 0;
DISPLAY LEFT (-1250 1800);
DISPLAY 1.021277 (-1250 1800);
PAINT WHITE (-1250 1800);
FORCENOTE
PR54 = CS00002JB13
(-1250 1725) 0;
DISPLAY LEFT (-1250 1725);
DISPLAY 1.021277 (-1250 1725);
PAINT WHITE (-1250 1725);
FORCENOTE
PR67 = CS36652FB03
(-1250 1575) 0;
DISPLAY LEFT (-1250 1575);
DISPLAY 1.021277 (-1250 1575);
PAINT WHITE (-1250 1575);
FORCENOTE
PR74 = CS37502FB05
(-1250 1500) 0;
DISPLAY LEFT (-1250 1500);
DISPLAY 1.021277 (-1250 1500);
PAINT WHITE (-1250 1500);
FORCENOTE
PR600 = CS24992FB07
(-1250 1425) 0;
DISPLAY LEFT (-1250 1425);
DISPLAY 1.021277 (-1250 1425);
PAINT WHITE (-1250 1425);
FORCENOTE
PC77,PC78 = CH31004KB17
(-1250 1350) 0;
DISPLAY LEFT (-1250 1350);
DISPLAY 1.021277 (-1250 1350);
PAINT WHITE (-1250 1350);
FORCENOTE
PC68,PC71 = EMPTY
(-1250 1275) 0;
DISPLAY LEFT (-1250 1275);
DISPLAY 1.021277 (-1250 1275);
PAINT WHITE (-1250 1275);
FORCENOTE
PC74 = CH21006JB10
(-1250 1200) 0;
DISPLAY LEFT (-1250 1200);
DISPLAY 1.021277 (-1250 1200);
PAINT WHITE (-1250 1200);
FORCENOTE
PC76=CH5103KEB01
(-1250 1125) 0;
DISPLAY LEFT (-1250 1125);
DISPLAY 1.021277 (-1250 1125);
PAINT WHITE (-1250 1125);
FORCENOTE
PR532,PR32 = EMPTY
(-1250 1650) 0;
DISPLAY LEFT (-1250 1650);
DISPLAY 1.021277 (-1250 1650);
PAINT WHITE (-1250 1650);
FORCENOTE
PU12 = TBD/XDPE192C3B
(-1250 2875) 0;
DISPLAY LEFT (-1250 2875);
DISPLAY 1.021277 (-1250 2875);
PAINT WHITE (-1250 2875);
FORCENOTE
PR53 = CS25362FB02
(-1250 2800) 0;
DISPLAY LEFT (-1250 2800);
DISPLAY 1.021277 (-1250 2800);
PAINT WHITE (-1250 2800);
FORCENOTE
PR54 = CS21002FB06
(-1250 2725) 0;
DISPLAY LEFT (-1250 2725);
DISPLAY 1.021277 (-1250 2725);
PAINT WHITE (-1250 2725);
FORCENOTE
PR532,PR32 = EMPTY
(-1250 2650) 0;
DISPLAY LEFT (-1250 2650);
DISPLAY 1.021277 (-1250 2650);
PAINT WHITE (-1250 2650);
FORCENOTE
PR68,PR69 = CS01002FB07
(-1250 2575) 0;
DISPLAY LEFT (-1250 2575);
DISPLAY 1.021277 (-1250 2575);
PAINT WHITE (-1250 2575);
FORCENOTE
PR67 = CS21072FB04
(-1250 2500) 0;
DISPLAY LEFT (-1250 2500);
DISPLAY 1.021277 (-1250 2500);
PAINT WHITE (-1250 2500);
FORCENOTE
PC76 = CH5103KEB01
(-1250 2425) 0;
DISPLAY LEFT (-1250 2425);
DISPLAY 1.021277 (-1250 2425);
PAINT WHITE (-1250 2425);
FORCENOTE
PC77,PC78 = CH11006JB00
(-1250 2350) 0;
DISPLAY LEFT (-1250 2350);
DISPLAY 1.021277 (-1250 2350);
PAINT WHITE (-1250 2350);
FORCENOTE
PC68,PC71 = CH12206KB14
(-1250 2275) 0;
DISPLAY LEFT (-1250 2275);
DISPLAY 1.021277 (-1250 2275);
PAINT WHITE (-1250 2275);
FORCENOTE
PC67 = CH3104J1B00
(-1250 2200) 0;
DISPLAY LEFT (-1250 2200);
DISPLAY 1.021277 (-1250 2200);
PAINT WHITE (-1250 2200);
FORCENOTE
RENESAS
(-8775 550) 0;
DISPLAY LEFT (-8775 550);
DISPLAY 0.638298 (-8775 550);
PAINT WHITE (-8775 550);
FORCENOTE
INFINEON
(-8775 475) 0;
DISPLAY LEFT (-8775 475);
DISPLAY 0.638298 (-8775 475);
PAINT WHITE (-8775 475);
FORCENOTE
VR
(-8775 650) 0;
DISPLAY LEFT (-8775 650);
DISPLAY 0.808511 (-8775 650);
PAINT WHITE (-8775 650);
FORCENOTE
0X4E
(-8325 475) 0;
DISPLAY LEFT (-8325 475);
DISPLAY 0.638298 (-8325 475);
PAINT WHITE (-8325 475);
FORCENOTE
0X4E
(-8325 400) 0;
DISPLAY LEFT (-8325 400);
DISPLAY 0.638298 (-8325 400);
PAINT WHITE (-8325 400);
FORCENOTE
MPS
(-8775 400) 0;
DISPLAY LEFT (-8775 400);
DISPLAY 0.638298 (-8775 400);
PAINT WHITE (-8775 400);
FORCENOTE
WORK FREQUENCY=600KHZ
(-1275 4500) 0;
DISPLAY LEFT (-1275 4500);
DISPLAY 0.936170 (-1275 4500);
PAINT WHITE (-1275 4500);
FORCENOTE
MIN AC=VID-EDC*LL-110MV
(-1275 6150) 0;
DISPLAY LEFT (-1275 6150);
DISPLAY 0.936170 (-1275 6150);
PAINT WHITE (-1275 6150);
FORCENOTE
PVDDCR_CPU1_P0 SPECFICATION
(-1275 6572) 0;
DISPLAY LEFT (-1275 6572);
DISPLAY 1.170213 (-1275 6572);
PAINT WHITE (-1275 6572);
FORCENOTE
TDC=120A
(-1275 4875) 0;
DISPLAY LEFT (-1275 4875);
DISPLAY 0.936170 (-1275 4875);
PAINT WHITE (-1275 4875);
FORCENOTE
/66.5K
(-7975 400) 0;
DISPLAY LEFT (-7975 400);
DISPLAY 0.638298 (-7975 400);
PAINT WHITE (-7975 400);
FORCENOTE
DC & AC=+/-80MV
(-1275 4950) 0;
DISPLAY LEFT (-1275 4950);
DISPLAY 0.936170 (-1275 4950);
PAINT WHITE (-1275 4950);
FORCENOTE
OCP=276A (EDC*1.2)
(-1275 5925) 0;
DISPLAY LEFT (-1275 5925);
DISPLAY 0.936170 (-1275 5925);
PAINT WHITE (-1275 5925);
FORCENOTE
MAX LOAD STEP=200A
(-1275 5850) 0;
DISPLAY LEFT (-1275 5850);
DISPLAY 0.936170 (-1275 5850);
PAINT WHITE (-1275 5850);
FORCENOTE
WORK FREQUENCY=600KHZ
(-1275 5625) 0;
DISPLAY LEFT (-1275 5625);
DISPLAY 0.936170 (-1275 5625);
PAINT WHITE (-1275 5625);
FORCENOTE
SVI3 ADDRESS=PORT1 (0X1)
(-1275 5475) 0;
DISPLAY LEFT (-1275 5475);
DISPLAY 0.936170 (-1275 5475);
PAINT WHITE (-1275 5475);
FORCENOTE
PVDDIO_P0 SPECFICATION
(-1275 5225) 0;
DISPLAY LEFT (-1275 5225);
DISPLAY 1.276596 (-1275 5225);
PAINT WHITE (-1275 5225);
FORCENOTE
DEFAULT POWER-ON VID=1.1V
(-1275 5100) 0;
DISPLAY LEFT (-1275 5100);
DISPLAY 0.936170 (-1275 5100);
PAINT WHITE (-1275 5100);
FORCENOTE
OCP=168A (EDC*1.2)
(-1275 4725) 0;
DISPLAY LEFT (-1275 4725);
DISPLAY 0.936170 (-1275 4725);
PAINT WHITE (-1275 4725);
FORCENOTE
IRM REV1.09
(-1275 5400) 0;
DISPLAY LEFT (-1275 5400);
DISPLAY 0.936170 (-1275 5400);
PAINT WHITE (-1275 5400);
FORCENOTE
EFFICIENCY > 90% @TDC
(-1275 4425) 0;
DISPLAY LEFT (-1275 4425);
DISPLAY 0.936170 (-1275 4425);
PAINT WHITE (-1275 4425);
FORCENOTE
DEFAULT POWER-ON VID=0.9V
(-1275 6450) 0;
DISPLAY LEFT (-1275 6450);
DISPLAY 0.936170 (-1275 6450);
PAINT WHITE (-1275 6450);
FORCENOTE
VID=0.55-1.5V
(-1275 6375) 0;
DISPLAY LEFT (-1275 6375);
DISPLAY 0.936170 (-1275 6375);
PAINT WHITE (-1275 6375);
FORCENOTE
DC=+/-20MV
(-1275 6300) 0;
DISPLAY LEFT (-1275 6300);
DISPLAY 0.936170 (-1275 6300);
PAINT WHITE (-1275 6300);
FORCENOTE
MAX AC=VID+200MV
(-1275 6225) 0;
DISPLAY LEFT (-1275 6225);
DISPLAY 0.936170 (-1275 6225);
PAINT WHITE (-1275 6225);
FORCENOTE
TDC=175A
(-1275 6075) 0;
DISPLAY LEFT (-1275 6075);
DISPLAY 0.936170 (-1275 6075);
PAINT WHITE (-1275 6075);
FORCENOTE
EDC=230A
(-1275 6000) 0;
DISPLAY LEFT (-1275 6000);
DISPLAY 0.936170 (-1275 6000);
PAINT WHITE (-1275 6000);
FORCENOTE
MAX LOAD RELEASE=200A
(-1275 5775) 0;
DISPLAY LEFT (-1275 5775);
DISPLAY 0.936170 (-1275 5775);
PAINT WHITE (-1275 5775);
FORCENOTE
LOAD-LINE=0.4MOHM
(-1275 5700) 0;
DISPLAY LEFT (-1275 5700);
DISPLAY 0.936170 (-1275 5700);
PAINT WHITE (-1275 5700);
FORCENOTE
EFFICIENCY > 90% @TDC
(-1275 5550) 0;
DISPLAY LEFT (-1275 5550);
DISPLAY 0.936170 (-1275 5550);
PAINT WHITE (-1275 5550);
FORCENOTE
VID=0.9-1.2V
(-1275 5025) 0;
DISPLAY LEFT (-1275 5025);
DISPLAY 0.936170 (-1275 5025);
PAINT WHITE (-1275 5025);
FORCENOTE
EDC=140A
(-1275 4800) 0;
DISPLAY LEFT (-1275 4800);
DISPLAY 0.936170 (-1275 4800);
PAINT WHITE (-1275 4800);
FORCENOTE
MAX LOAD STEP=44A
(-1275 4650) 0;
DISPLAY LEFT (-1275 4650);
DISPLAY 0.936170 (-1275 4650);
PAINT WHITE (-1275 4650);
FORCENOTE
MAX LOAD RELEASE=37A
(-1275 4575) 0;
DISPLAY LEFT (-1275 4575);
DISPLAY 0.936170 (-1275 4575);
PAINT WHITE (-1275 4575);
FORCENOTE
SVI3 ADDRESS=PORT1 (0X2)
(-1275 4350) 0;
DISPLAY LEFT (-1275 4350);
DISPLAY 0.936170 (-1275 4350);
PAINT WHITE (-1275 4350);
FORCENOTE
IRM REV1.09
(-1275 4275) 0;
DISPLAY LEFT (-1275 4275);
DISPLAY 0.936170 (-1275 4275);
PAINT WHITE (-1275 4275);
FORCENOTE
DIFFERENTIAL PAIR
(-8750 2675) 0;
DISPLAY LEFT (-8750 2675);
DISPLAY 1.021277 (-8750 2675);
PAINT WHITE (-8750 2675);
FORCENOTE
TRACE WIDTH = 10MIL
(-8750 2600) 0;
DISPLAY LEFT (-8750 2600);
DISPLAY 1.021277 (-8750 2600);
PAINT WHITE (-8750 2600);
FORCENOTE
TRACE SPACING = 5MIL
(-8750 2525) 0;
DISPLAY LEFT (-8750 2525);
DISPLAY 1.021277 (-8750 2525);
PAINT WHITE (-8750 2525);
FORCENOTE
CONFIG/R
(-7975 650) 0;
DISPLAY LEFT (-7975 650);
DISPLAY 0.808511 (-7975 650);
PAINT WHITE (-7975 650);
FORCENOTE
/1.07K
(-7975 475) 0;
DISPLAY LEFT (-7975 475);
DISPLAY 0.638298 (-7975 475);
PAINT WHITE (-7975 475);
FORCENOTE
DIFFERENTIAL PAIR
(-8600 3750) 0;
DISPLAY LEFT (-8600 3750);
DISPLAY 1.021277 (-8600 3750);
PAINT WHITE (-8600 3750);
FORCENOTE
TRACE WIDTH = 10MIL
(-8600 3675) 0;
DISPLAY LEFT (-8600 3675);
DISPLAY 1.021277 (-8600 3675);
PAINT WHITE (-8600 3675);
FORCENOTE
TRACE SPACING = 5MIL
(-8600 3600) 0;
DISPLAY LEFT (-8600 3600);
DISPLAY 1.021277 (-8600 3600);
PAINT WHITE (-8600 3600);
FORCENOTE
2ND SOURCE:INFENEON BOM
(-1250 2975) 0;
DISPLAY LEFT (-1250 2975);
DISPLAY 1.276596 (-1250 2975);
PAINT WHITE (-1250 2975);
FORCENOTE
PU12 = TBD/RAA229620GNP#HA0
(-1250 3150) 0;
DISPLAY LEFT (-1250 3150);
DISPLAY 1.021277 (-1250 3150);
PAINT WHITE (-1250 3150);
FORCENOTE
MAIN SOURCE:RENESAS BOM
(-1250 3250) 0;
DISPLAY LEFT (-1250 3250);
DISPLAY 1.276596 (-1250 3250);
PAINT WHITE (-1250 3250);
QUIT
